FILE_TYPE = MACRO_DRAWING;
SET COLOR_WIRE YELLOW;
SET COLOR_PROP ORANGE;
SET COLOR_DOT WHITE;
SET COLOR_ARC YELLOW;
SET COLOR_BODY GREEN;
SET COLOR_NOTE PURPLE;
SET PROP_DISPLAY VALUE;
SET PAGE_NUMBER P104;
FORCEADD OFFPAGE..5
(-8250 2000);
FORCEPROP 2 LAST $XR0 44 
J 0
(-8474 2000);
DISPLAY 0.638298 (-8474 2000);
PAINT MONO (-8474 2000);
FORCEPROP 2 LAST PATH I1
J 0
(-8500 2050);
DISPLAY 1.021277 (-8500 2050);
DISPLAY INVISIBLE (-8500 2050);
FORCEPROP 1 LAST COMMENT_BODY TRUE
J 0
(-8150 1925);
DISPLAY 0.872340 (-8150 1925);
PAINT GREEN (-8150 1925);
DISPLAY INVISIBLE (-8150 1925);
FORCEPROP 1 LAST OFFPAGE TRUE
J 0
(-7925 1875);
DISPLAY 0.872340 (-7925 1875);
PAINT GREEN (-7925 1875);
DISPLAY INVISIBLE (-7925 1875);
FORCEPROP 2 LAST CDS_LIB mstr_standard
J 0
(-8250 2000);
DISPLAY 0.808511 (-8250 2000);
DISPLAY INVISIBLE (-8250 2000);
FORCEADD OFFPAGE..6
(-8250 3600);
FORCEPROP 2 LAST $XR0 44 
J 0
(-8529 3600);
DISPLAY 0.638298 (-8529 3600);
PAINT MONO (-8529 3600);
FORCEPROP 2 LAST PATH I10
J 0
(-8525 3650);
DISPLAY 1.021277 (-8525 3650);
DISPLAY INVISIBLE (-8525 3650);
FORCEPROP 1 LAST COMMENT_BODY TRUE
J 0
(-8150 3525);
DISPLAY 0.872340 (-8150 3525);
PAINT GREEN (-8150 3525);
DISPLAY INVISIBLE (-8150 3525);
FORCEPROP 1 LAST OFFPAGE TRUE
J 0
(-7925 3475);
DISPLAY 0.872340 (-7925 3475);
PAINT GREEN (-7925 3475);
DISPLAY INVISIBLE (-7925 3475);
FORCEPROP 2 LAST CDS_LIB mstr_standard
J 0
(-8250 3600);
DISPLAY 0.723404 (-8250 3600);
PAINT MONO (-8250 3600);
DISPLAY INVISIBLE (-8250 3600);
FORCEADD TAP..1
(-5950 4200);
FORCEPROP 3 LASTPIN (-6000 4200) SIG_NAME M_H_CPU1_SA_DQ<7>
J 0
(-5990 4210);
DISPLAY 0.659574 (-5990 4210);
PAINT MONO (-5990 4210);
DISPLAY INVISIBLE (-5990 4210);
FORCEPROP 1 LASTPIN (-6000 4200) BN 7
J 0
(-6012 4208);
DISPLAY 0.489362 (-6012 4208);
PAINT GREEN (-6012 4208);
FORCEPROP 2 LAST CDS_LIB mstr_standard
J 0
(-5950 4200);
DISPLAY 0.723404 (-5950 4200);
PAINT MONO (-5950 4200);
DISPLAY INVISIBLE (-5950 4200);
FORCEPROP 1 LAST BODY_TYPE PLUMBING
J 0
(-5950 4250);
DISPLAY 0.872340 (-5950 4250);
PAINT GREEN (-5950 4250);
DISPLAY INVISIBLE (-5950 4250);
FORCEPROP 1 LAST HDL_TAP TRUE
J 0
(-5625 4075);
DISPLAY 0.872340 (-5625 4075);
DISPLAY INVISIBLE (-5625 4075);
FORCEPROP 1 LAST PATH I100
J 0
(-5952 4200);
DISPLAY 0.872340 (-5952 4200);
PAINT GREEN (-5952 4200);
DISPLAY INVISIBLE (-5952 4200);
FORCEADD TAP..1
(-5950 4250);
FORCEPROP 3 LASTPIN (-6000 4250) SIG_NAME M_H_CPU1_SA_DQ<8>
J 0
(-5990 4260);
DISPLAY 0.659574 (-5990 4260);
PAINT MONO (-5990 4260);
DISPLAY INVISIBLE (-5990 4260);
FORCEPROP 1 LASTPIN (-6000 4250) BN 8
J 0
(-6012 4258);
DISPLAY 0.489362 (-6012 4258);
PAINT GREEN (-6012 4258);
FORCEPROP 2 LAST CDS_LIB mstr_standard
J 0
(-5950 4250);
DISPLAY 0.723404 (-5950 4250);
PAINT MONO (-5950 4250);
DISPLAY INVISIBLE (-5950 4250);
FORCEPROP 1 LAST BODY_TYPE PLUMBING
J 0
(-5950 4300);
DISPLAY 0.872340 (-5950 4300);
PAINT GREEN (-5950 4300);
DISPLAY INVISIBLE (-5950 4300);
FORCEPROP 1 LAST HDL_TAP TRUE
J 0
(-5625 4125);
DISPLAY 0.872340 (-5625 4125);
DISPLAY INVISIBLE (-5625 4125);
FORCEPROP 1 LAST PATH I101
J 0
(-5952 4250);
DISPLAY 0.872340 (-5952 4250);
PAINT GREEN (-5952 4250);
DISPLAY INVISIBLE (-5952 4250);
FORCEADD TAP..1
(-5950 4300);
FORCEPROP 3 LASTPIN (-6000 4300) SIG_NAME M_H_CPU1_SA_DQ<9>
J 0
(-5990 4310);
DISPLAY 0.659574 (-5990 4310);
PAINT MONO (-5990 4310);
DISPLAY INVISIBLE (-5990 4310);
FORCEPROP 1 LASTPIN (-6000 4300) BN 9
J 0
(-6012 4308);
DISPLAY 0.489362 (-6012 4308);
PAINT GREEN (-6012 4308);
FORCEPROP 2 LAST CDS_LIB mstr_standard
J 0
(-5950 4300);
DISPLAY 0.723404 (-5950 4300);
PAINT MONO (-5950 4300);
DISPLAY INVISIBLE (-5950 4300);
FORCEPROP 1 LAST BODY_TYPE PLUMBING
J 0
(-5950 4350);
DISPLAY 0.872340 (-5950 4350);
PAINT GREEN (-5950 4350);
DISPLAY INVISIBLE (-5950 4350);
FORCEPROP 1 LAST HDL_TAP TRUE
J 0
(-5625 4175);
DISPLAY 0.872340 (-5625 4175);
DISPLAY INVISIBLE (-5625 4175);
FORCEPROP 1 LAST PATH I102
J 0
(-5952 4300);
DISPLAY 0.872340 (-5952 4300);
PAINT GREEN (-5952 4300);
DISPLAY INVISIBLE (-5952 4300);
FORCEADD TAP..1
(-5950 4400);
FORCEPROP 3 LASTPIN (-6000 4400) SIG_NAME M_H_CPU1_SA_DQ<11>
J 0
(-5990 4410);
DISPLAY 0.659574 (-5990 4410);
PAINT MONO (-5990 4410);
DISPLAY INVISIBLE (-5990 4410);
FORCEPROP 1 LASTPIN (-6000 4400) BN 11
J 0
(-6012 4408);
DISPLAY 0.489362 (-6012 4408);
PAINT GREEN (-6012 4408);
FORCEPROP 2 LAST CDS_LIB mstr_standard
J 0
(-5950 4400);
DISPLAY 0.723404 (-5950 4400);
PAINT MONO (-5950 4400);
DISPLAY INVISIBLE (-5950 4400);
FORCEPROP 1 LAST BODY_TYPE PLUMBING
J 0
(-5950 4450);
DISPLAY 0.872340 (-5950 4450);
PAINT GREEN (-5950 4450);
DISPLAY INVISIBLE (-5950 4450);
FORCEPROP 1 LAST HDL_TAP TRUE
J 0
(-5625 4275);
DISPLAY 0.872340 (-5625 4275);
DISPLAY INVISIBLE (-5625 4275);
FORCEPROP 1 LAST PATH I103
J 0
(-5952 4400);
DISPLAY 0.872340 (-5952 4400);
PAINT GREEN (-5952 4400);
DISPLAY INVISIBLE (-5952 4400);
FORCEADD TAP..1
(-5950 4350);
FORCEPROP 3 LASTPIN (-6000 4350) SIG_NAME M_H_CPU1_SA_DQ<10>
J 0
(-5990 4360);
DISPLAY 0.659574 (-5990 4360);
PAINT MONO (-5990 4360);
DISPLAY INVISIBLE (-5990 4360);
FORCEPROP 1 LASTPIN (-6000 4350) BN 10
J 0
(-6012 4358);
DISPLAY 0.489362 (-6012 4358);
PAINT GREEN (-6012 4358);
FORCEPROP 2 LAST CDS_LIB mstr_standard
J 0
(-5950 4350);
DISPLAY 0.723404 (-5950 4350);
PAINT MONO (-5950 4350);
DISPLAY INVISIBLE (-5950 4350);
FORCEPROP 1 LAST BODY_TYPE PLUMBING
J 0
(-5950 4400);
DISPLAY 0.872340 (-5950 4400);
PAINT GREEN (-5950 4400);
DISPLAY INVISIBLE (-5950 4400);
FORCEPROP 1 LAST HDL_TAP TRUE
J 0
(-5625 4225);
DISPLAY 0.872340 (-5625 4225);
DISPLAY INVISIBLE (-5625 4225);
FORCEPROP 1 LAST PATH I104
J 0
(-5952 4350);
DISPLAY 0.872340 (-5952 4350);
PAINT GREEN (-5952 4350);
DISPLAY INVISIBLE (-5952 4350);
FORCEADD TAP..1
(-5950 4450);
FORCEPROP 3 LASTPIN (-6000 4450) SIG_NAME M_H_CPU1_SA_DQ<12>
J 0
(-5990 4460);
DISPLAY 0.659574 (-5990 4460);
PAINT MONO (-5990 4460);
DISPLAY INVISIBLE (-5990 4460);
FORCEPROP 1 LASTPIN (-6000 4450) BN 12
J 0
(-6012 4458);
DISPLAY 0.489362 (-6012 4458);
PAINT GREEN (-6012 4458);
FORCEPROP 2 LAST CDS_LIB mstr_standard
J 0
(-5950 4450);
DISPLAY 0.723404 (-5950 4450);
PAINT MONO (-5950 4450);
DISPLAY INVISIBLE (-5950 4450);
FORCEPROP 1 LAST BODY_TYPE PLUMBING
J 0
(-5950 4500);
DISPLAY 0.872340 (-5950 4500);
PAINT GREEN (-5950 4500);
DISPLAY INVISIBLE (-5950 4500);
FORCEPROP 1 LAST HDL_TAP TRUE
J 0
(-5625 4325);
DISPLAY 0.872340 (-5625 4325);
DISPLAY INVISIBLE (-5625 4325);
FORCEPROP 1 LAST PATH I105
J 0
(-5952 4450);
DISPLAY 0.872340 (-5952 4450);
PAINT GREEN (-5952 4450);
DISPLAY INVISIBLE (-5952 4450);
FORCEADD TAP..1
(-5950 4500);
FORCEPROP 3 LASTPIN (-6000 4500) SIG_NAME M_H_CPU1_SA_DQ<13>
J 0
(-5990 4510);
DISPLAY 0.659574 (-5990 4510);
PAINT MONO (-5990 4510);
DISPLAY INVISIBLE (-5990 4510);
FORCEPROP 1 LASTPIN (-6000 4500) BN 13
J 0
(-6012 4508);
DISPLAY 0.489362 (-6012 4508);
PAINT GREEN (-6012 4508);
FORCEPROP 2 LAST CDS_LIB mstr_standard
J 0
(-5950 4500);
DISPLAY 0.723404 (-5950 4500);
PAINT MONO (-5950 4500);
DISPLAY INVISIBLE (-5950 4500);
FORCEPROP 1 LAST BODY_TYPE PLUMBING
J 0
(-5950 4550);
DISPLAY 0.872340 (-5950 4550);
PAINT GREEN (-5950 4550);
DISPLAY INVISIBLE (-5950 4550);
FORCEPROP 1 LAST HDL_TAP TRUE
J 0
(-5625 4375);
DISPLAY 0.872340 (-5625 4375);
DISPLAY INVISIBLE (-5625 4375);
FORCEPROP 1 LAST PATH I106
J 0
(-5952 4500);
DISPLAY 0.872340 (-5952 4500);
PAINT GREEN (-5952 4500);
DISPLAY INVISIBLE (-5952 4500);
FORCEADD TAP..1
(-5950 4550);
FORCEPROP 3 LASTPIN (-6000 4550) SIG_NAME M_H_CPU1_SA_DQ<14>
J 0
(-5990 4560);
DISPLAY 0.659574 (-5990 4560);
PAINT MONO (-5990 4560);
DISPLAY INVISIBLE (-5990 4560);
FORCEPROP 1 LASTPIN (-6000 4550) BN 14
J 0
(-6012 4558);
DISPLAY 0.489362 (-6012 4558);
PAINT GREEN (-6012 4558);
FORCEPROP 2 LAST CDS_LIB mstr_standard
J 0
(-5950 4550);
DISPLAY 0.723404 (-5950 4550);
PAINT MONO (-5950 4550);
DISPLAY INVISIBLE (-5950 4550);
FORCEPROP 1 LAST BODY_TYPE PLUMBING
J 0
(-5950 4600);
DISPLAY 0.872340 (-5950 4600);
PAINT GREEN (-5950 4600);
DISPLAY INVISIBLE (-5950 4600);
FORCEPROP 1 LAST HDL_TAP TRUE
J 0
(-5625 4425);
DISPLAY 0.872340 (-5625 4425);
DISPLAY INVISIBLE (-5625 4425);
FORCEPROP 1 LAST PATH I107
J 0
(-5952 4550);
DISPLAY 0.872340 (-5952 4550);
PAINT GREEN (-5952 4550);
DISPLAY INVISIBLE (-5952 4550);
FORCEADD TAP..1
(-5950 4650);
FORCEPROP 3 LASTPIN (-6000 4650) SIG_NAME M_H_CPU1_SA_DQ<16>
J 0
(-5990 4660);
DISPLAY 0.659574 (-5990 4660);
PAINT MONO (-5990 4660);
DISPLAY INVISIBLE (-5990 4660);
FORCEPROP 1 LASTPIN (-6000 4650) BN 16
J 0
(-6012 4658);
DISPLAY 0.489362 (-6012 4658);
PAINT GREEN (-6012 4658);
FORCEPROP 2 LAST CDS_LIB mstr_standard
J 0
(-5950 4650);
DISPLAY 0.723404 (-5950 4650);
PAINT MONO (-5950 4650);
DISPLAY INVISIBLE (-5950 4650);
FORCEPROP 1 LAST BODY_TYPE PLUMBING
J 0
(-5950 4700);
DISPLAY 0.872340 (-5950 4700);
PAINT GREEN (-5950 4700);
DISPLAY INVISIBLE (-5950 4700);
FORCEPROP 1 LAST HDL_TAP TRUE
J 0
(-5625 4525);
DISPLAY 0.872340 (-5625 4525);
DISPLAY INVISIBLE (-5625 4525);
FORCEPROP 1 LAST PATH I108
J 0
(-5952 4650);
DISPLAY 0.872340 (-5952 4650);
PAINT GREEN (-5952 4650);
DISPLAY INVISIBLE (-5952 4650);
FORCEADD TAP..1
(-5950 4600);
FORCEPROP 3 LASTPIN (-6000 4600) SIG_NAME M_H_CPU1_SA_DQ<15>
J 0
(-5990 4610);
DISPLAY 0.659574 (-5990 4610);
PAINT MONO (-5990 4610);
DISPLAY INVISIBLE (-5990 4610);
FORCEPROP 1 LASTPIN (-6000 4600) BN 15
J 0
(-6012 4608);
DISPLAY 0.489362 (-6012 4608);
PAINT GREEN (-6012 4608);
FORCEPROP 2 LAST CDS_LIB mstr_standard
J 0
(-5950 4600);
DISPLAY 0.723404 (-5950 4600);
PAINT MONO (-5950 4600);
DISPLAY INVISIBLE (-5950 4600);
FORCEPROP 1 LAST BODY_TYPE PLUMBING
J 0
(-5950 4650);
DISPLAY 0.872340 (-5950 4650);
PAINT GREEN (-5950 4650);
DISPLAY INVISIBLE (-5950 4650);
FORCEPROP 1 LAST HDL_TAP TRUE
J 0
(-5625 4475);
DISPLAY 0.872340 (-5625 4475);
DISPLAY INVISIBLE (-5625 4475);
FORCEPROP 1 LAST PATH I109
J 0
(-5952 4600);
DISPLAY 0.872340 (-5952 4600);
PAINT GREEN (-5952 4600);
DISPLAY INVISIBLE (-5952 4600);
FORCEADD OFFPAGE..1
(-8250 4100);
FORCEPROP 2 LAST $XR0 44 
J 0
(-8501 4100);
DISPLAY 0.638298 (-8501 4100);
PAINT MONO (-8501 4100);
FORCEPROP 2 LAST PATH I11
J 0
(-8450 4150);
DISPLAY 1.021277 (-8450 4150);
DISPLAY INVISIBLE (-8450 4150);
FORCEPROP 1 LAST COMMENT_BODY TRUE
J 0
(-8125 4000);
DISPLAY 0.872340 (-8125 4000);
PAINT GREEN (-8125 4000);
DISPLAY INVISIBLE (-8125 4000);
FORCEPROP 1 LAST OFFPAGE TRUE
J 0
(-7925 3975);
DISPLAY 0.872340 (-7925 3975);
PAINT GREEN (-7925 3975);
DISPLAY INVISIBLE (-7925 3975);
FORCEPROP 2 LAST CDS_LIB mstr_standard
J 0
(-8250 4100);
DISPLAY 0.808511 (-8250 4100);
DISPLAY INVISIBLE (-8250 4100);
FORCEADD TAP..1
(-5950 4750);
FORCEPROP 3 LASTPIN (-6000 4750) SIG_NAME M_H_CPU1_SA_DQ<18>
J 0
(-5990 4760);
DISPLAY 0.659574 (-5990 4760);
PAINT MONO (-5990 4760);
DISPLAY INVISIBLE (-5990 4760);
FORCEPROP 1 LASTPIN (-6000 4750) BN 18
J 0
(-6012 4758);
DISPLAY 0.489362 (-6012 4758);
PAINT GREEN (-6012 4758);
FORCEPROP 2 LAST CDS_LIB mstr_standard
J 0
(-5950 4750);
DISPLAY 0.723404 (-5950 4750);
PAINT MONO (-5950 4750);
DISPLAY INVISIBLE (-5950 4750);
FORCEPROP 1 LAST BODY_TYPE PLUMBING
J 0
(-5950 4800);
DISPLAY 0.872340 (-5950 4800);
PAINT GREEN (-5950 4800);
DISPLAY INVISIBLE (-5950 4800);
FORCEPROP 1 LAST HDL_TAP TRUE
J 0
(-5625 4625);
DISPLAY 0.872340 (-5625 4625);
DISPLAY INVISIBLE (-5625 4625);
FORCEPROP 1 LAST PATH I110
J 0
(-5952 4750);
DISPLAY 0.872340 (-5952 4750);
PAINT GREEN (-5952 4750);
DISPLAY INVISIBLE (-5952 4750);
FORCEADD TAP..1
(-5950 4700);
FORCEPROP 3 LASTPIN (-6000 4700) SIG_NAME M_H_CPU1_SA_DQ<17>
J 0
(-5990 4710);
DISPLAY 0.659574 (-5990 4710);
PAINT MONO (-5990 4710);
DISPLAY INVISIBLE (-5990 4710);
FORCEPROP 1 LASTPIN (-6000 4700) BN 17
J 0
(-6012 4708);
DISPLAY 0.489362 (-6012 4708);
PAINT GREEN (-6012 4708);
FORCEPROP 2 LAST CDS_LIB mstr_standard
J 0
(-5950 4700);
DISPLAY 0.723404 (-5950 4700);
PAINT MONO (-5950 4700);
DISPLAY INVISIBLE (-5950 4700);
FORCEPROP 1 LAST BODY_TYPE PLUMBING
J 0
(-5950 4750);
DISPLAY 0.872340 (-5950 4750);
PAINT GREEN (-5950 4750);
DISPLAY INVISIBLE (-5950 4750);
FORCEPROP 1 LAST HDL_TAP TRUE
J 0
(-5625 4575);
DISPLAY 0.872340 (-5625 4575);
DISPLAY INVISIBLE (-5625 4575);
FORCEPROP 1 LAST PATH I111
J 0
(-5952 4700);
DISPLAY 0.872340 (-5952 4700);
PAINT GREEN (-5952 4700);
DISPLAY INVISIBLE (-5952 4700);
FORCEADD TAP..1
(-5950 4800);
FORCEPROP 3 LASTPIN (-6000 4800) SIG_NAME M_H_CPU1_SA_DQ<19>
J 0
(-5990 4810);
DISPLAY 0.659574 (-5990 4810);
PAINT MONO (-5990 4810);
DISPLAY INVISIBLE (-5990 4810);
FORCEPROP 1 LASTPIN (-6000 4800) BN 19
J 0
(-6012 4808);
DISPLAY 0.489362 (-6012 4808);
PAINT GREEN (-6012 4808);
FORCEPROP 2 LAST CDS_LIB mstr_standard
J 0
(-5950 4800);
DISPLAY 0.723404 (-5950 4800);
PAINT MONO (-5950 4800);
DISPLAY INVISIBLE (-5950 4800);
FORCEPROP 1 LAST BODY_TYPE PLUMBING
J 0
(-5950 4850);
DISPLAY 0.872340 (-5950 4850);
PAINT GREEN (-5950 4850);
DISPLAY INVISIBLE (-5950 4850);
FORCEPROP 1 LAST HDL_TAP TRUE
J 0
(-5625 4675);
DISPLAY 0.872340 (-5625 4675);
DISPLAY INVISIBLE (-5625 4675);
FORCEPROP 1 LAST PATH I112
J 0
(-5952 4800);
DISPLAY 0.872340 (-5952 4800);
PAINT GREEN (-5952 4800);
DISPLAY INVISIBLE (-5952 4800);
FORCEADD TAP..1
(-5950 4900);
FORCEPROP 3 LASTPIN (-6000 4900) SIG_NAME M_H_CPU1_SA_DQ<21>
J 0
(-5990 4910);
DISPLAY 0.659574 (-5990 4910);
PAINT MONO (-5990 4910);
DISPLAY INVISIBLE (-5990 4910);
FORCEPROP 1 LASTPIN (-6000 4900) BN 21
J 0
(-6012 4908);
DISPLAY 0.489362 (-6012 4908);
PAINT GREEN (-6012 4908);
FORCEPROP 2 LAST CDS_LIB mstr_standard
J 0
(-5950 4900);
DISPLAY 0.723404 (-5950 4900);
PAINT MONO (-5950 4900);
DISPLAY INVISIBLE (-5950 4900);
FORCEPROP 1 LAST BODY_TYPE PLUMBING
J 0
(-5950 4950);
DISPLAY 0.872340 (-5950 4950);
PAINT GREEN (-5950 4950);
DISPLAY INVISIBLE (-5950 4950);
FORCEPROP 1 LAST HDL_TAP TRUE
J 0
(-5625 4775);
DISPLAY 0.872340 (-5625 4775);
DISPLAY INVISIBLE (-5625 4775);
FORCEPROP 1 LAST PATH I113
J 0
(-5952 4900);
DISPLAY 0.872340 (-5952 4900);
PAINT GREEN (-5952 4900);
DISPLAY INVISIBLE (-5952 4900);
FORCEADD TAP..1
(-5950 4850);
FORCEPROP 3 LASTPIN (-6000 4850) SIG_NAME M_H_CPU1_SA_DQ<20>
J 0
(-5990 4860);
DISPLAY 0.659574 (-5990 4860);
PAINT MONO (-5990 4860);
DISPLAY INVISIBLE (-5990 4860);
FORCEPROP 1 LASTPIN (-6000 4850) BN 20
J 0
(-6012 4858);
DISPLAY 0.489362 (-6012 4858);
PAINT GREEN (-6012 4858);
FORCEPROP 2 LAST CDS_LIB mstr_standard
J 0
(-5950 4850);
DISPLAY 0.723404 (-5950 4850);
PAINT MONO (-5950 4850);
DISPLAY INVISIBLE (-5950 4850);
FORCEPROP 1 LAST BODY_TYPE PLUMBING
J 0
(-5950 4900);
DISPLAY 0.872340 (-5950 4900);
PAINT GREEN (-5950 4900);
DISPLAY INVISIBLE (-5950 4900);
FORCEPROP 1 LAST HDL_TAP TRUE
J 0
(-5625 4725);
DISPLAY 0.872340 (-5625 4725);
DISPLAY INVISIBLE (-5625 4725);
FORCEPROP 1 LAST PATH I114
J 0
(-5952 4850);
DISPLAY 0.872340 (-5952 4850);
PAINT GREEN (-5952 4850);
DISPLAY INVISIBLE (-5952 4850);
FORCEADD TAP..1
(-5950 4950);
FORCEPROP 3 LASTPIN (-6000 4950) SIG_NAME M_H_CPU1_SA_DQ<22>
J 0
(-5990 4960);
DISPLAY 0.659574 (-5990 4960);
PAINT MONO (-5990 4960);
DISPLAY INVISIBLE (-5990 4960);
FORCEPROP 1 LASTPIN (-6000 4950) BN 22
J 0
(-6012 4958);
DISPLAY 0.489362 (-6012 4958);
PAINT GREEN (-6012 4958);
FORCEPROP 2 LAST CDS_LIB mstr_standard
J 0
(-5950 4950);
DISPLAY 0.723404 (-5950 4950);
PAINT MONO (-5950 4950);
DISPLAY INVISIBLE (-5950 4950);
FORCEPROP 1 LAST BODY_TYPE PLUMBING
J 0
(-5950 5000);
DISPLAY 0.872340 (-5950 5000);
PAINT GREEN (-5950 5000);
DISPLAY INVISIBLE (-5950 5000);
FORCEPROP 1 LAST HDL_TAP TRUE
J 0
(-5625 4825);
DISPLAY 0.872340 (-5625 4825);
DISPLAY INVISIBLE (-5625 4825);
FORCEPROP 1 LAST PATH I115
J 0
(-5952 4950);
DISPLAY 0.872340 (-5952 4950);
PAINT GREEN (-5952 4950);
DISPLAY INVISIBLE (-5952 4950);
FORCEADD TAP..1
(-5950 5000);
FORCEPROP 3 LASTPIN (-6000 5000) SIG_NAME M_H_CPU1_SA_DQ<23>
J 0
(-5990 5010);
DISPLAY 0.659574 (-5990 5010);
PAINT MONO (-5990 5010);
DISPLAY INVISIBLE (-5990 5010);
FORCEPROP 1 LASTPIN (-6000 5000) BN 23
J 0
(-6012 5008);
DISPLAY 0.489362 (-6012 5008);
PAINT GREEN (-6012 5008);
FORCEPROP 2 LAST CDS_LIB mstr_standard
J 0
(-5950 5000);
DISPLAY 0.723404 (-5950 5000);
PAINT MONO (-5950 5000);
DISPLAY INVISIBLE (-5950 5000);
FORCEPROP 1 LAST BODY_TYPE PLUMBING
J 0
(-5950 5050);
DISPLAY 0.872340 (-5950 5050);
PAINT GREEN (-5950 5050);
DISPLAY INVISIBLE (-5950 5050);
FORCEPROP 1 LAST HDL_TAP TRUE
J 0
(-5625 4875);
DISPLAY 0.872340 (-5625 4875);
DISPLAY INVISIBLE (-5625 4875);
FORCEPROP 1 LAST PATH I116
J 0
(-5952 5000);
DISPLAY 0.872340 (-5952 5000);
PAINT GREEN (-5952 5000);
DISPLAY INVISIBLE (-5952 5000);
FORCEADD TAP..1
(-5950 5100);
FORCEPROP 3 LASTPIN (-6000 5100) SIG_NAME M_H_CPU1_SA_DQ<25>
J 0
(-5990 5110);
DISPLAY 0.659574 (-5990 5110);
PAINT MONO (-5990 5110);
DISPLAY INVISIBLE (-5990 5110);
FORCEPROP 1 LASTPIN (-6000 5100) BN 25
J 0
(-6012 5108);
DISPLAY 0.489362 (-6012 5108);
PAINT GREEN (-6012 5108);
FORCEPROP 2 LAST CDS_LIB mstr_standard
J 0
(-5950 5100);
DISPLAY 0.723404 (-5950 5100);
PAINT MONO (-5950 5100);
DISPLAY INVISIBLE (-5950 5100);
FORCEPROP 1 LAST BODY_TYPE PLUMBING
J 0
(-5950 5150);
DISPLAY 0.872340 (-5950 5150);
PAINT GREEN (-5950 5150);
DISPLAY INVISIBLE (-5950 5150);
FORCEPROP 1 LAST HDL_TAP TRUE
J 0
(-5625 4975);
DISPLAY 0.872340 (-5625 4975);
DISPLAY INVISIBLE (-5625 4975);
FORCEPROP 1 LAST PATH I117
J 0
(-5952 5100);
DISPLAY 0.872340 (-5952 5100);
PAINT GREEN (-5952 5100);
DISPLAY INVISIBLE (-5952 5100);
FORCEADD TAP..1
(-5950 5050);
FORCEPROP 3 LASTPIN (-6000 5050) SIG_NAME M_H_CPU1_SA_DQ<24>
J 0
(-5990 5060);
DISPLAY 0.659574 (-5990 5060);
PAINT MONO (-5990 5060);
DISPLAY INVISIBLE (-5990 5060);
FORCEPROP 1 LASTPIN (-6000 5050) BN 24
J 0
(-6012 5058);
DISPLAY 0.489362 (-6012 5058);
PAINT GREEN (-6012 5058);
FORCEPROP 2 LAST CDS_LIB mstr_standard
J 0
(-5950 5050);
DISPLAY 0.723404 (-5950 5050);
PAINT MONO (-5950 5050);
DISPLAY INVISIBLE (-5950 5050);
FORCEPROP 1 LAST BODY_TYPE PLUMBING
J 0
(-5950 5100);
DISPLAY 0.872340 (-5950 5100);
PAINT GREEN (-5950 5100);
DISPLAY INVISIBLE (-5950 5100);
FORCEPROP 1 LAST HDL_TAP TRUE
J 0
(-5625 4925);
DISPLAY 0.872340 (-5625 4925);
DISPLAY INVISIBLE (-5625 4925);
FORCEPROP 1 LAST PATH I118
J 0
(-5952 5050);
DISPLAY 0.872340 (-5952 5050);
PAINT GREEN (-5952 5050);
DISPLAY INVISIBLE (-5952 5050);
FORCEADD TAP..1
(-5950 5150);
FORCEPROP 3 LASTPIN (-6000 5150) SIG_NAME M_H_CPU1_SA_DQ<26>
J 0
(-5990 5160);
DISPLAY 0.659574 (-5990 5160);
PAINT MONO (-5990 5160);
DISPLAY INVISIBLE (-5990 5160);
FORCEPROP 1 LASTPIN (-6000 5150) BN 26
J 0
(-6012 5158);
DISPLAY 0.489362 (-6012 5158);
PAINT GREEN (-6012 5158);
FORCEPROP 2 LAST CDS_LIB mstr_standard
J 0
(-5950 5150);
DISPLAY 0.723404 (-5950 5150);
PAINT MONO (-5950 5150);
DISPLAY INVISIBLE (-5950 5150);
FORCEPROP 1 LAST BODY_TYPE PLUMBING
J 0
(-5950 5200);
DISPLAY 0.872340 (-5950 5200);
PAINT GREEN (-5950 5200);
DISPLAY INVISIBLE (-5950 5200);
FORCEPROP 1 LAST HDL_TAP TRUE
J 0
(-5625 5025);
DISPLAY 0.872340 (-5625 5025);
DISPLAY INVISIBLE (-5625 5025);
FORCEPROP 1 LAST PATH I119
J 0
(-5952 5150);
DISPLAY 0.872340 (-5952 5150);
PAINT GREEN (-5952 5150);
DISPLAY INVISIBLE (-5952 5150);
FORCEADD OFFPAGE..6
(-8250 4050);
FORCEPROP 2 LAST $XR0 44 
J 0
(-8529 4050);
DISPLAY 0.638298 (-8529 4050);
PAINT MONO (-8529 4050);
FORCEPROP 2 LAST PATH I12
J 0
(-8525 4100);
DISPLAY 1.021277 (-8525 4100);
DISPLAY INVISIBLE (-8525 4100);
FORCEPROP 1 LAST COMMENT_BODY TRUE
J 0
(-8150 3975);
DISPLAY 0.872340 (-8150 3975);
PAINT GREEN (-8150 3975);
DISPLAY INVISIBLE (-8150 3975);
FORCEPROP 1 LAST OFFPAGE TRUE
J 0
(-7925 3925);
DISPLAY 0.872340 (-7925 3925);
PAINT GREEN (-7925 3925);
DISPLAY INVISIBLE (-7925 3925);
FORCEPROP 2 LAST CDS_LIB mstr_standard
J 0
(-8250 4050);
DISPLAY 0.723404 (-8250 4050);
PAINT MONO (-8250 4050);
DISPLAY INVISIBLE (-8250 4050);
FORCEADD TAP..1
(-5950 5300);
FORCEPROP 3 LASTPIN (-6000 5300) SIG_NAME M_H_CPU1_SA_DQ<29>
J 0
(-5990 5310);
DISPLAY 0.659574 (-5990 5310);
PAINT MONO (-5990 5310);
DISPLAY INVISIBLE (-5990 5310);
FORCEPROP 1 LASTPIN (-6000 5300) BN 29
J 0
(-6012 5308);
DISPLAY 0.489362 (-6012 5308);
PAINT GREEN (-6012 5308);
FORCEPROP 2 LAST CDS_LIB mstr_standard
J 0
(-5950 5300);
DISPLAY 0.723404 (-5950 5300);
PAINT MONO (-5950 5300);
DISPLAY INVISIBLE (-5950 5300);
FORCEPROP 1 LAST BODY_TYPE PLUMBING
J 0
(-5950 5350);
DISPLAY 0.872340 (-5950 5350);
PAINT GREEN (-5950 5350);
DISPLAY INVISIBLE (-5950 5350);
FORCEPROP 1 LAST HDL_TAP TRUE
J 0
(-5625 5175);
DISPLAY 0.872340 (-5625 5175);
DISPLAY INVISIBLE (-5625 5175);
FORCEPROP 1 LAST PATH I120
J 0
(-5952 5300);
DISPLAY 0.872340 (-5952 5300);
PAINT GREEN (-5952 5300);
DISPLAY INVISIBLE (-5952 5300);
FORCEADD TAP..1
(-5950 5250);
FORCEPROP 3 LASTPIN (-6000 5250) SIG_NAME M_H_CPU1_SA_DQ<28>
J 0
(-5990 5260);
DISPLAY 0.659574 (-5990 5260);
PAINT MONO (-5990 5260);
DISPLAY INVISIBLE (-5990 5260);
FORCEPROP 1 LASTPIN (-6000 5250) BN 28
J 0
(-6012 5258);
DISPLAY 0.489362 (-6012 5258);
PAINT GREEN (-6012 5258);
FORCEPROP 2 LAST CDS_LIB mstr_standard
J 0
(-5950 5250);
DISPLAY 0.723404 (-5950 5250);
PAINT MONO (-5950 5250);
DISPLAY INVISIBLE (-5950 5250);
FORCEPROP 1 LAST BODY_TYPE PLUMBING
J 0
(-5950 5300);
DISPLAY 0.872340 (-5950 5300);
PAINT GREEN (-5950 5300);
DISPLAY INVISIBLE (-5950 5300);
FORCEPROP 1 LAST HDL_TAP TRUE
J 0
(-5625 5125);
DISPLAY 0.872340 (-5625 5125);
DISPLAY INVISIBLE (-5625 5125);
FORCEPROP 1 LAST PATH I121
J 0
(-5952 5250);
DISPLAY 0.872340 (-5952 5250);
PAINT GREEN (-5952 5250);
DISPLAY INVISIBLE (-5952 5250);
FORCEADD TAP..1
(-5950 5200);
FORCEPROP 3 LASTPIN (-6000 5200) SIG_NAME M_H_CPU1_SA_DQ<27>
J 0
(-5990 5210);
DISPLAY 0.659574 (-5990 5210);
PAINT MONO (-5990 5210);
DISPLAY INVISIBLE (-5990 5210);
FORCEPROP 1 LASTPIN (-6000 5200) BN 27
J 0
(-6012 5208);
DISPLAY 0.489362 (-6012 5208);
PAINT GREEN (-6012 5208);
FORCEPROP 2 LAST CDS_LIB mstr_standard
J 0
(-5950 5200);
DISPLAY 0.723404 (-5950 5200);
PAINT MONO (-5950 5200);
DISPLAY INVISIBLE (-5950 5200);
FORCEPROP 1 LAST BODY_TYPE PLUMBING
J 0
(-5950 5250);
DISPLAY 0.872340 (-5950 5250);
PAINT GREEN (-5950 5250);
DISPLAY INVISIBLE (-5950 5250);
FORCEPROP 1 LAST HDL_TAP TRUE
J 0
(-5625 5075);
DISPLAY 0.872340 (-5625 5075);
DISPLAY INVISIBLE (-5625 5075);
FORCEPROP 1 LAST PATH I122
J 0
(-5952 5200);
DISPLAY 0.872340 (-5952 5200);
PAINT GREEN (-5952 5200);
DISPLAY INVISIBLE (-5952 5200);
FORCEADD TAP..1
(-5950 5350);
FORCEPROP 3 LASTPIN (-6000 5350) SIG_NAME M_H_CPU1_SA_DQ<30>
J 0
(-5990 5360);
DISPLAY 0.659574 (-5990 5360);
PAINT MONO (-5990 5360);
DISPLAY INVISIBLE (-5990 5360);
FORCEPROP 1 LASTPIN (-6000 5350) BN 30
J 0
(-6012 5358);
DISPLAY 0.489362 (-6012 5358);
PAINT GREEN (-6012 5358);
FORCEPROP 2 LAST CDS_LIB mstr_standard
J 0
(-5950 5350);
DISPLAY 0.723404 (-5950 5350);
PAINT MONO (-5950 5350);
DISPLAY INVISIBLE (-5950 5350);
FORCEPROP 1 LAST BODY_TYPE PLUMBING
J 0
(-5950 5400);
DISPLAY 0.872340 (-5950 5400);
PAINT GREEN (-5950 5400);
DISPLAY INVISIBLE (-5950 5400);
FORCEPROP 1 LAST HDL_TAP TRUE
J 0
(-5625 5225);
DISPLAY 0.872340 (-5625 5225);
DISPLAY INVISIBLE (-5625 5225);
FORCEPROP 1 LAST PATH I123
J 0
(-5952 5350);
DISPLAY 0.872340 (-5952 5350);
PAINT GREEN (-5952 5350);
DISPLAY INVISIBLE (-5952 5350);
FORCEADD TAP..1
(-5950 5400);
FORCEPROP 3 LASTPIN (-6000 5400) SIG_NAME M_H_CPU1_SA_DQ<31>
J 0
(-5990 5410);
DISPLAY 0.659574 (-5990 5410);
PAINT MONO (-5990 5410);
DISPLAY INVISIBLE (-5990 5410);
FORCEPROP 1 LASTPIN (-6000 5400) BN 31
J 0
(-6012 5408);
DISPLAY 0.489362 (-6012 5408);
PAINT GREEN (-6012 5408);
FORCEPROP 2 LAST CDS_LIB mstr_standard
J 0
(-5950 5400);
DISPLAY 0.723404 (-5950 5400);
PAINT MONO (-5950 5400);
DISPLAY INVISIBLE (-5950 5400);
FORCEPROP 1 LAST BODY_TYPE PLUMBING
J 0
(-5950 5450);
DISPLAY 0.872340 (-5950 5450);
PAINT GREEN (-5950 5450);
DISPLAY INVISIBLE (-5950 5450);
FORCEPROP 1 LAST HDL_TAP TRUE
J 0
(-5625 5275);
DISPLAY 0.872340 (-5625 5275);
DISPLAY INVISIBLE (-5625 5275);
FORCEPROP 1 LAST PATH I124
J 0
(-5952 5400);
DISPLAY 0.872340 (-5952 5400);
PAINT GREEN (-5952 5400);
DISPLAY INVISIBLE (-5952 5400);
FORCEADD OFFPAGE..3
(-5325 5450);
FORCEPROP 2 LAST $XR0 44 
J 0
(-5111 5450);
DISPLAY 0.638298 (-5111 5450);
PAINT MONO (-5111 5450);
FORCEPROP 2 LAST PATH I125
J 0
(-5100 5500);
DISPLAY 1.021277 (-5100 5500);
DISPLAY INVISIBLE (-5100 5500);
FORCEPROP 1 LAST COMMENT_BODY TRUE
J 0
(-5375 5350);
DISPLAY 0.872340 (-5375 5350);
PAINT GREEN (-5375 5350);
DISPLAY INVISIBLE (-5375 5350);
FORCEPROP 1 LAST OFFPAGE TRUE
J 0
(-5000 5325);
DISPLAY 0.872340 (-5000 5325);
PAINT GREEN (-5000 5325);
DISPLAY INVISIBLE (-5000 5325);
FORCEPROP 2 LAST CDS_LIB mstr_standard
J 0
(-5325 5450);
DISPLAY 0.723404 (-5325 5450);
PAINT MONO (-5325 5450);
DISPLAY INVISIBLE (-5325 5450);
FORCEADD OFFPAGE..5
(-7150 1250);
FORCEPROP 2 LAST $XR0 104 
J 0
(-7405 1250);
DISPLAY 0.638298 (-7405 1250);
PAINT MONO (-7405 1250);
FORCEPROP 2 LAST PATH I126
J 0
(-7400 1300);
DISPLAY 1.021277 (-7400 1300);
DISPLAY INVISIBLE (-7400 1300);
FORCEPROP 1 LAST COMMENT_BODY TRUE
J 0
(-7050 1175);
DISPLAY 0.872340 (-7050 1175);
PAINT GREEN (-7050 1175);
DISPLAY INVISIBLE (-7050 1175);
FORCEPROP 1 LAST OFFPAGE TRUE
J 0
(-6825 1125);
DISPLAY 0.872340 (-6825 1125);
PAINT GREEN (-6825 1125);
DISPLAY INVISIBLE (-6825 1125);
FORCEPROP 2 LAST BOM_COST MEM
J 0
(-7225 1325);
DISPLAY 0.808511 (-7225 1325);
DISPLAY INVISIBLE (-7225 1325);
FORCEPROP 2 LAST CDS_LIB mstr_standard
J 0
(-7150 1250);
DISPLAY 0.808511 (-7150 1250);
DISPLAY INVISIBLE (-7150 1250);
FORCEADD GND..1
(-6375 850);
FORCEPROP 3 LASTPIN (-6375 900) SIG_NAME GND\g
J 0
(-6365 910);
DISPLAY 0.659574 (-6365 910);
PAINT MONO (-6365 910);
DISPLAY INVISIBLE (-6365 910);
FORCEPROP 1 LAST SIZE 1B
J 0
(-6300 800);
DISPLAY 0.851064 (-6300 800);
PAINT GREEN (-6300 800);
DISPLAY INVISIBLE (-6300 800);
FORCEPROP 2 LAST CDS_LIB mstr_symbols
J 0
(-6375 850);
DISPLAY 0.808511 (-6375 850);
DISPLAY INVISIBLE (-6375 850);
FORCEPROP 2 LAST BOM_COST MEM
J 0
(-6475 925);
DISPLAY 0.808511 (-6475 925);
DISPLAY INVISIBLE (-6475 925);
FORCEPROP 1 LAST BODY_TYPE PLUMBING
J 0
(-6420 807);
DISPLAY 0.340426 (-6420 807);
PAINT GREEN (-6420 807);
DISPLAY INVISIBLE (-6420 807);
FORCEPROP 1 LAST PATH I127
J 0
(-6300 850);
DISPLAY 0.872340 (-6300 850);
PAINT AQUA (-6300 850);
DISPLAY INVISIBLE (-6300 850);
FORCEPROP 1 LAST VOLTAGE 0.0
J 0
(-6420 807);
DISPLAY 0.723404 (-6420 807);
PAINT SKYBLUE (-6420 807);
DISPLAY INVISIBLE (-6420 807);
FORCEPROP 1 LAST HDL_POWER GND
J 0
(-6375 1000);
DISPLAY 0.851064 (-6375 1000);
PAINT GREEN (-6375 1000);
DISPLAY INVISIBLE (-6375 1000);
FORCEADD Q_RES..2
(-6375 1075);
FORCEPROP 1 LAST LOCATION R774
J 0
(-6330 1200);
DISPLAY 0.489362 (-6330 1200);
PAINT SKYBLUE (-6330 1200);
FORCEPROP 0 LAST $SEC 1
J 0
(-6325 1250);
DISPLAY 0.680851 (-6325 1250);
PAINT MONO (-6325 1250);
DISPLAY INVISIBLE (-6325 1250);
FORCEPROP 0 LAST CDS_SEC 1
J 0
(-6325 1250);
DISPLAY 1.021277 (-6325 1250);
DISPLAY INVISIBLE (-6325 1250);
FORCEPROP 1 LASTPIN (-6375 1175) $PN 1
J 0
(-6370 1137);
DISPLAY 0.489362 (-6370 1137);
PAINT MONO (-6370 1137);
FORCEPROP 1 LASTPIN (-6375 975) $PN 2
J 0
(-6370 985);
DISPLAY 0.489362 (-6370 985);
PAINT MONO (-6370 985);
FORCEPROP 1 LAST WATTAGE 1/16W
J 0
(-6335 1050);
DISPLAY 0.489362 (-6335 1050);
PAINT SKYBLUE (-6335 1050);
FORCEPROP 1 LAST MATERIAL CHIP
J 0
(-6335 1000);
DISPLAY 0.489362 (-6335 1000);
PAINT SKYBLUE (-6335 1000);
FORCEPROP 1 LAST TOLERANCE 1%
J 0
(-6330 1100);
DISPLAY 0.489362 (-6330 1100);
PAINT SKYBLUE (-6330 1100);
FORCEPROP 1 LAST VALUE 15.4K
J 0
(-6330 1150);
DISPLAY 0.489362 (-6330 1150);
PAINT SKYBLUE (-6330 1150);
FORCEPROP 1 LAST PART_NUMBER CS31542FB02
J 0
(-6335 950);
DISPLAY 0.489362 (-6335 950);
PAINT SKYBLUE (-6335 950);
FORCEPROP 1 LAST PACK_TYPE 0402LF
J 0
(-6335 900);
DISPLAY 0.489362 (-6335 900);
PAINT SKYBLUE (-6335 900);
FORCEPROP 2 LAST CDS_LIB pure_quanta
J 0
(-6375 1075);
DISPLAY INVISIBLE (-6375 1075);
FORCEPROP 1 LAST PATH I128
J 0
(-6325 1250);
DISPLAY 0.978723 (-6325 1250);
PAINT WHITE (-6325 1250);
DISPLAY INVISIBLE (-6325 1250);
FORCEADD OFFPAGE..1
(-8250 4150);
FORCEPROP 2 LAST $XR0 44 
J 0
(-8501 4150);
DISPLAY 0.638298 (-8501 4150);
PAINT MONO (-8501 4150);
FORCEPROP 2 LAST PATH I13
J 0
(-8450 4200);
DISPLAY 1.021277 (-8450 4200);
DISPLAY INVISIBLE (-8450 4200);
FORCEPROP 1 LAST COMMENT_BODY TRUE
J 0
(-8125 4050);
DISPLAY 0.872340 (-8125 4050);
PAINT GREEN (-8125 4050);
DISPLAY INVISIBLE (-8125 4050);
FORCEPROP 1 LAST OFFPAGE TRUE
J 0
(-7925 4025);
DISPLAY 0.872340 (-7925 4025);
PAINT GREEN (-7925 4025);
DISPLAY INVISIBLE (-7925 4025);
FORCEPROP 2 LAST CDS_LIB mstr_standard
J 0
(-8250 4150);
DISPLAY 0.723404 (-8250 4150);
PAINT MONO (-8250 4150);
DISPLAY INVISIBLE (-8250 4150);
FORCEADD OFFPAGE..1
(-8250 4250);
FORCEPROP 2 LAST $XR0 44 
J 0
(-8501 4250);
DISPLAY 0.638298 (-8501 4250);
PAINT MONO (-8501 4250);
FORCEPROP 2 LAST PATH I14
J 0
(-8450 4300);
DISPLAY 1.021277 (-8450 4300);
DISPLAY INVISIBLE (-8450 4300);
FORCEPROP 1 LAST COMMENT_BODY TRUE
J 0
(-8125 4150);
DISPLAY 0.872340 (-8125 4150);
PAINT GREEN (-8125 4150);
DISPLAY INVISIBLE (-8125 4150);
FORCEPROP 1 LAST OFFPAGE TRUE
J 0
(-7925 4125);
DISPLAY 0.872340 (-7925 4125);
PAINT GREEN (-7925 4125);
DISPLAY INVISIBLE (-7925 4125);
FORCEPROP 2 LAST CDS_LIB mstr_standard
J 0
(-8250 4250);
DISPLAY 0.808511 (-8250 4250);
DISPLAY INVISIBLE (-8250 4250);
FORCEADD GND..1
(-2125 1875);
FORCEPROP 3 LASTPIN (-2125 1925) SIG_NAME GND\g
J 0
(-2115 1935);
DISPLAY 0.659574 (-2115 1935);
PAINT MONO (-2115 1935);
DISPLAY INVISIBLE (-2115 1935);
FORCEPROP 1 LAST SIZE 1B
J 0
(-2050 1825);
DISPLAY 0.851064 (-2050 1825);
PAINT GREEN (-2050 1825);
DISPLAY INVISIBLE (-2050 1825);
FORCEPROP 2 LAST CDS_LIB mstr_symbols
J 0
(-2125 1875);
DISPLAY 0.723404 (-2125 1875);
DISPLAY INVISIBLE (-2125 1875);
FORCEPROP 1 LAST BODY_TYPE PLUMBING
J 0
(-2170 1832);
DISPLAY 0.340426 (-2170 1832);
PAINT GREEN (-2170 1832);
DISPLAY INVISIBLE (-2170 1832);
FORCEPROP 1 LAST PATH I140
J 0
(-2050 1875);
DISPLAY 0.872340 (-2050 1875);
PAINT AQUA (-2050 1875);
DISPLAY INVISIBLE (-2050 1875);
FORCEPROP 1 LAST VOLTAGE 0.0
J 0
(-2170 1832);
DISPLAY 0.723404 (-2170 1832);
PAINT SKYBLUE (-2170 1832);
DISPLAY INVISIBLE (-2170 1832);
FORCEPROP 1 LAST HDL_POWER GND
J 0
(-2125 2025);
DISPLAY 0.851064 (-2125 2025);
PAINT GREEN (-2125 2025);
DISPLAY INVISIBLE (-2125 2025);
FORCEADD GND..1
(-325 1650);
FORCEPROP 3 LASTPIN (-325 1700) SIG_NAME GND\g
J 0
(-315 1710);
DISPLAY 0.659574 (-315 1710);
PAINT MONO (-315 1710);
DISPLAY INVISIBLE (-315 1710);
FORCEPROP 1 LAST SIZE 1B
J 0
(-250 1600);
DISPLAY 0.851064 (-250 1600);
PAINT GREEN (-250 1600);
DISPLAY INVISIBLE (-250 1600);
FORCEPROP 2 LAST CDS_LIB mstr_symbols
J 0
(-325 1650);
DISPLAY 0.723404 (-325 1650);
DISPLAY INVISIBLE (-325 1650);
FORCEPROP 1 LAST BODY_TYPE PLUMBING
J 0
(-370 1607);
DISPLAY 0.340426 (-370 1607);
PAINT GREEN (-370 1607);
DISPLAY INVISIBLE (-370 1607);
FORCEPROP 1 LAST PATH I141
J 0
(-250 1650);
DISPLAY 0.872340 (-250 1650);
PAINT AQUA (-250 1650);
DISPLAY INVISIBLE (-250 1650);
FORCEPROP 1 LAST VOLTAGE 0.0
J 0
(-370 1607);
DISPLAY 0.723404 (-370 1607);
PAINT SKYBLUE (-370 1607);
DISPLAY INVISIBLE (-370 1607);
FORCEPROP 1 LAST HDL_POWER GND
J 0
(-325 1800);
DISPLAY 0.851064 (-325 1800);
PAINT GREEN (-325 1800);
DISPLAY INVISIBLE (-325 1800);
FORCEADD OFFPAGE..1
(-8250 4300);
FORCEPROP 2 LAST $XR0 44 
J 0
(-8501 4300);
DISPLAY 0.638298 (-8501 4300);
PAINT MONO (-8501 4300);
FORCEPROP 2 LAST PATH I15
J 0
(-8450 4350);
DISPLAY 1.021277 (-8450 4350);
DISPLAY INVISIBLE (-8450 4350);
FORCEPROP 1 LAST COMMENT_BODY TRUE
J 0
(-8125 4200);
DISPLAY 0.872340 (-8125 4200);
PAINT GREEN (-8125 4200);
DISPLAY INVISIBLE (-8125 4200);
FORCEPROP 1 LAST OFFPAGE TRUE
J 0
(-7925 4175);
DISPLAY 0.872340 (-7925 4175);
PAINT GREEN (-7925 4175);
DISPLAY INVISIBLE (-7925 4175);
FORCEPROP 2 LAST CDS_LIB mstr_standard
J 0
(-8250 4300);
DISPLAY 0.723404 (-8250 4300);
PAINT MONO (-8250 4300);
DISPLAY INVISIBLE (-8250 4300);
FORCEADD OFFPAGE..1
(-8250 4400);
FORCEPROP 2 LAST $XR0 44 
J 0
(-8501 4400);
DISPLAY 0.638298 (-8501 4400);
PAINT MONO (-8501 4400);
FORCEPROP 2 LAST PATH I16
J 0
(-8450 4450);
DISPLAY 1.021277 (-8450 4450);
DISPLAY INVISIBLE (-8450 4450);
FORCEPROP 1 LAST COMMENT_BODY TRUE
J 0
(-8125 4300);
DISPLAY 0.872340 (-8125 4300);
PAINT GREEN (-8125 4300);
DISPLAY INVISIBLE (-8125 4300);
FORCEPROP 1 LAST OFFPAGE TRUE
J 0
(-7925 4275);
DISPLAY 0.872340 (-7925 4275);
PAINT GREEN (-7925 4275);
DISPLAY INVISIBLE (-7925 4275);
FORCEPROP 2 LAST CDS_LIB mstr_standard
J 0
(-8250 4400);
DISPLAY 0.808511 (-8250 4400);
DISPLAY INVISIBLE (-8250 4400);
FORCEADD OFFPAGE..1
(-8250 4550);
FORCEPROP 2 LAST $XR0 44 
J 0
(-8501 4550);
DISPLAY 0.638298 (-8501 4550);
PAINT MONO (-8501 4550);
FORCEPROP 2 LAST PATH I17
J 0
(-8450 4600);
DISPLAY 1.021277 (-8450 4600);
DISPLAY INVISIBLE (-8450 4600);
FORCEPROP 1 LAST COMMENT_BODY TRUE
J 0
(-8125 4450);
DISPLAY 0.872340 (-8125 4450);
PAINT GREEN (-8125 4450);
DISPLAY INVISIBLE (-8125 4450);
FORCEPROP 1 LAST OFFPAGE TRUE
J 0
(-7925 4425);
DISPLAY 0.872340 (-7925 4425);
PAINT GREEN (-7925 4425);
DISPLAY INVISIBLE (-7925 4425);
FORCEPROP 2 LAST CDS_LIB mstr_standard
J 0
(-8250 4550);
DISPLAY 0.808511 (-8250 4550);
DISPLAY INVISIBLE (-8250 4550);
FORCEADD SCONN288_DDR506112002KQ..3
(-1225 3650);
FORCEPROP 1 LAST LOCATION J27
J 0
(-1675 5625);
DISPLAY 0.468085 (-1675 5625);
PAINT SKYBLUE (-1675 5625);
FORCEPROP 0 LAST $SEC 3
J 0
(-1675 5775);
DISPLAY 0.680851 (-1675 5775);
PAINT MONO (-1675 5775);
DISPLAY INVISIBLE (-1675 5775);
FORCEPROP 2 LAST CDS_SEC 3
J 0
(-1675 5775);
DISPLAY 1.021277 (-1675 5775);
DISPLAY INVISIBLE (-1675 5775);
FORCEPROP 0 LASTPIN (-625 2050) $PN G1
J 0
(-615 2060);
DISPLAY 0.680851 (-615 2060);
PAINT MONO (-615 2060);
FORCEPROP 0 LASTPIN (-625 2000) $PN G2
J 0
(-615 2010);
DISPLAY 0.680851 (-615 2010);
PAINT MONO (-615 2010);
FORCEPROP 0 LASTPIN (-625 1950) $PN G3
J 0
(-615 1960);
DISPLAY 0.680851 (-615 1960);
PAINT MONO (-615 1960);
FORCEPROP 0 LASTPIN (-1825 5200) $PN 1
J 2
(-1835 5210);
DISPLAY 0.680851 (-1835 5210);
PAINT MONO (-1835 5210);
FORCEPROP 0 LASTPIN (-1825 5250) $PN 145
J 2
(-1835 5260);
DISPLAY 0.680851 (-1835 5260);
PAINT MONO (-1835 5260);
FORCEPROP 0 LASTPIN (-1825 5300) $PN 146
J 2
(-1835 5310);
DISPLAY 0.680851 (-1835 5310);
PAINT MONO (-1835 5310);
FORCEPROP 0 LASTPIN (-625 2150) $PN 6
J 0
(-615 2160);
DISPLAY 0.680851 (-615 2160);
PAINT MONO (-615 2160);
FORCEPROP 0 LASTPIN (-625 2200) $PN 8
J 0
(-615 2210);
DISPLAY 0.680851 (-615 2210);
PAINT MONO (-615 2210);
FORCEPROP 0 LASTPIN (-625 2250) $PN 10
J 0
(-615 2260);
DISPLAY 0.680851 (-615 2260);
PAINT MONO (-615 2260);
FORCEPROP 0 LASTPIN (-625 2300) $PN 13
J 0
(-615 2310);
DISPLAY 0.680851 (-615 2310);
PAINT MONO (-615 2310);
FORCEPROP 0 LASTPIN (-625 2350) $PN 15
J 0
(-615 2360);
DISPLAY 0.680851 (-615 2360);
PAINT MONO (-615 2360);
FORCEPROP 0 LASTPIN (-625 2400) $PN 17
J 0
(-615 2410);
DISPLAY 0.680851 (-615 2410);
PAINT MONO (-615 2410);
FORCEPROP 0 LASTPIN (-625 2450) $PN 19
J 0
(-615 2460);
DISPLAY 0.680851 (-615 2460);
PAINT MONO (-615 2460);
FORCEPROP 0 LASTPIN (-625 2500) $PN 21
J 0
(-615 2510);
DISPLAY 0.680851 (-615 2510);
PAINT MONO (-615 2510);
FORCEPROP 0 LASTPIN (-625 2550) $PN 24
J 0
(-615 2560);
DISPLAY 0.680851 (-615 2560);
PAINT MONO (-615 2560);
FORCEPROP 0 LASTPIN (-625 2600) $PN 26
J 0
(-615 2610);
DISPLAY 0.680851 (-615 2610);
PAINT MONO (-615 2610);
FORCEPROP 0 LASTPIN (-625 2650) $PN 28
J 0
(-615 2660);
DISPLAY 0.680851 (-615 2660);
PAINT MONO (-615 2660);
FORCEPROP 0 LASTPIN (-625 2700) $PN 30
J 0
(-615 2710);
DISPLAY 0.680851 (-615 2710);
PAINT MONO (-615 2710);
FORCEPROP 0 LASTPIN (-625 2750) $PN 32
J 0
(-615 2760);
DISPLAY 0.680851 (-615 2760);
PAINT MONO (-615 2760);
FORCEPROP 0 LASTPIN (-625 2800) $PN 35
J 0
(-615 2810);
DISPLAY 0.680851 (-615 2810);
PAINT MONO (-615 2810);
FORCEPROP 0 LASTPIN (-625 2850) $PN 37
J 0
(-615 2860);
DISPLAY 0.680851 (-615 2860);
PAINT MONO (-615 2860);
FORCEPROP 0 LASTPIN (-625 2900) $PN 39
J 0
(-615 2910);
DISPLAY 0.680851 (-615 2910);
PAINT MONO (-615 2910);
FORCEPROP 0 LASTPIN (-625 2950) $PN 41
J 0
(-615 2960);
DISPLAY 0.680851 (-615 2960);
PAINT MONO (-615 2960);
FORCEPROP 0 LASTPIN (-625 3000) $PN 43
J 0
(-615 3010);
DISPLAY 0.680851 (-615 3010);
PAINT MONO (-615 3010);
FORCEPROP 0 LASTPIN (-625 3050) $PN 46
J 0
(-615 3060);
DISPLAY 0.680851 (-615 3060);
PAINT MONO (-615 3060);
FORCEPROP 0 LASTPIN (-625 3100) $PN 48
J 0
(-615 3110);
DISPLAY 0.680851 (-615 3110);
PAINT MONO (-615 3110);
FORCEPROP 0 LASTPIN (-625 3150) $PN 50
J 0
(-615 3160);
DISPLAY 0.680851 (-615 3160);
PAINT MONO (-615 3160);
FORCEPROP 0 LASTPIN (-625 3200) $PN 52
J 0
(-615 3210);
DISPLAY 0.680851 (-615 3210);
PAINT MONO (-615 3210);
FORCEPROP 0 LASTPIN (-625 3250) $PN 54
J 0
(-615 3260);
DISPLAY 0.680851 (-615 3260);
PAINT MONO (-615 3260);
FORCEPROP 0 LASTPIN (-625 3300) $PN 57
J 0
(-615 3310);
DISPLAY 0.680851 (-615 3310);
PAINT MONO (-615 3310);
FORCEPROP 0 LASTPIN (-625 3350) $PN 59
J 0
(-615 3360);
DISPLAY 0.680851 (-615 3360);
PAINT MONO (-615 3360);
FORCEPROP 0 LASTPIN (-625 3400) $PN 61
J 0
(-615 3410);
DISPLAY 0.680851 (-615 3410);
PAINT MONO (-615 3410);
FORCEPROP 0 LASTPIN (-625 3450) $PN 63
J 0
(-615 3460);
DISPLAY 0.680851 (-615 3460);
PAINT MONO (-615 3460);
FORCEPROP 0 LASTPIN (-625 3500) $PN 65
J 0
(-615 3510);
DISPLAY 0.680851 (-615 3510);
PAINT MONO (-615 3510);
FORCEPROP 0 LASTPIN (-625 3550) $PN 67
J 0
(-615 3560);
DISPLAY 0.680851 (-615 3560);
PAINT MONO (-615 3560);
FORCEPROP 0 LASTPIN (-625 3600) $PN 69
J 0
(-615 3610);
DISPLAY 0.680851 (-615 3610);
PAINT MONO (-615 3610);
FORCEPROP 0 LASTPIN (-625 3650) $PN 71
J 0
(-615 3660);
DISPLAY 0.680851 (-615 3660);
PAINT MONO (-615 3660);
FORCEPROP 0 LASTPIN (-625 3700) $PN 73
J 0
(-615 3710);
DISPLAY 0.680851 (-615 3710);
PAINT MONO (-615 3710);
FORCEPROP 0 LASTPIN (-625 3750) $PN 75
J 0
(-615 3760);
DISPLAY 0.680851 (-615 3760);
PAINT MONO (-615 3760);
FORCEPROP 0 LASTPIN (-625 3800) $PN 77
J 0
(-615 3810);
DISPLAY 0.680851 (-615 3810);
PAINT MONO (-615 3810);
FORCEPROP 0 LASTPIN (-625 3850) $PN 79
J 0
(-615 3860);
DISPLAY 0.680851 (-615 3860);
PAINT MONO (-615 3860);
FORCEPROP 0 LASTPIN (-625 3900) $PN 81
J 0
(-615 3910);
DISPLAY 0.680851 (-615 3910);
PAINT MONO (-615 3910);
FORCEPROP 0 LASTPIN (-625 3950) $PN 83
J 0
(-615 3960);
DISPLAY 0.680851 (-615 3960);
PAINT MONO (-615 3960);
FORCEPROP 0 LASTPIN (-625 4000) $PN 85
J 0
(-615 4010);
DISPLAY 0.680851 (-615 4010);
PAINT MONO (-615 4010);
FORCEPROP 0 LASTPIN (-625 4050) $PN 88
J 0
(-615 4060);
DISPLAY 0.680851 (-615 4060);
PAINT MONO (-615 4060);
FORCEPROP 0 LASTPIN (-625 4100) $PN 90
J 0
(-615 4110);
DISPLAY 0.680851 (-615 4110);
PAINT MONO (-615 4110);
FORCEPROP 0 LASTPIN (-625 4150) $PN 92
J 0
(-615 4160);
DISPLAY 0.680851 (-615 4160);
PAINT MONO (-615 4160);
FORCEPROP 0 LASTPIN (-625 4200) $PN 95
J 0
(-615 4210);
DISPLAY 0.680851 (-615 4210);
PAINT MONO (-615 4210);
FORCEPROP 0 LASTPIN (-625 4250) $PN 97
J 0
(-615 4260);
DISPLAY 0.680851 (-615 4260);
PAINT MONO (-615 4260);
FORCEPROP 0 LASTPIN (-625 4300) $PN 99
J 0
(-615 4310);
DISPLAY 0.680851 (-615 4310);
PAINT MONO (-615 4310);
FORCEPROP 0 LASTPIN (-625 4350) $PN 101
J 0
(-615 4360);
DISPLAY 0.680851 (-615 4360);
PAINT MONO (-615 4360);
FORCEPROP 0 LASTPIN (-625 4400) $PN 103
J 0
(-615 4410);
DISPLAY 0.680851 (-615 4410);
PAINT MONO (-615 4410);
FORCEPROP 0 LASTPIN (-625 4450) $PN 106
J 0
(-615 4460);
DISPLAY 0.680851 (-615 4460);
PAINT MONO (-615 4460);
FORCEPROP 0 LASTPIN (-625 4500) $PN 108
J 0
(-615 4510);
DISPLAY 0.680851 (-615 4510);
PAINT MONO (-615 4510);
FORCEPROP 0 LASTPIN (-625 4550) $PN 110
J 0
(-615 4560);
DISPLAY 0.680851 (-615 4560);
PAINT MONO (-615 4560);
FORCEPROP 0 LASTPIN (-625 4600) $PN 112
J 0
(-615 4610);
DISPLAY 0.680851 (-615 4610);
PAINT MONO (-615 4610);
FORCEPROP 0 LASTPIN (-625 4650) $PN 114
J 0
(-615 4660);
DISPLAY 0.680851 (-615 4660);
PAINT MONO (-615 4660);
FORCEPROP 0 LASTPIN (-625 4700) $PN 117
J 0
(-615 4710);
DISPLAY 0.680851 (-615 4710);
PAINT MONO (-615 4710);
FORCEPROP 0 LASTPIN (-625 4750) $PN 119
J 0
(-615 4760);
DISPLAY 0.680851 (-615 4760);
PAINT MONO (-615 4760);
FORCEPROP 0 LASTPIN (-625 4800) $PN 121
J 0
(-615 4810);
DISPLAY 0.680851 (-615 4810);
PAINT MONO (-615 4810);
FORCEPROP 0 LASTPIN (-625 4850) $PN 123
J 0
(-615 4860);
DISPLAY 0.680851 (-615 4860);
PAINT MONO (-615 4860);
FORCEPROP 0 LASTPIN (-625 4900) $PN 125
J 0
(-615 4910);
DISPLAY 0.680851 (-615 4910);
PAINT MONO (-615 4910);
FORCEPROP 0 LASTPIN (-625 4950) $PN 128
J 0
(-615 4960);
DISPLAY 0.680851 (-615 4960);
PAINT MONO (-615 4960);
FORCEPROP 0 LASTPIN (-625 5000) $PN 130
J 0
(-615 5010);
DISPLAY 0.680851 (-615 5010);
PAINT MONO (-615 5010);
FORCEPROP 0 LASTPIN (-625 5050) $PN 132
J 0
(-615 5060);
DISPLAY 0.680851 (-615 5060);
PAINT MONO (-615 5060);
FORCEPROP 0 LASTPIN (-625 5100) $PN 134
J 0
(-615 5110);
DISPLAY 0.680851 (-615 5110);
PAINT MONO (-615 5110);
FORCEPROP 0 LASTPIN (-625 5150) $PN 136
J 0
(-615 5160);
DISPLAY 0.680851 (-615 5160);
PAINT MONO (-615 5160);
FORCEPROP 0 LASTPIN (-625 5200) $PN 139
J 0
(-615 5210);
DISPLAY 0.680851 (-615 5210);
PAINT MONO (-615 5210);
FORCEPROP 0 LASTPIN (-625 5250) $PN 141
J 0
(-615 5260);
DISPLAY 0.680851 (-615 5260);
PAINT MONO (-615 5260);
FORCEPROP 0 LASTPIN (-625 5300) $PN 143
J 0
(-615 5310);
DISPLAY 0.680851 (-615 5310);
PAINT MONO (-615 5310);
FORCEPROP 0 LASTPIN (-1825 2050) $PN 151
J 2
(-1835 2060);
DISPLAY 0.680851 (-1835 2060);
PAINT MONO (-1835 2060);
FORCEPROP 0 LASTPIN (-1825 2100) $PN 153
J 2
(-1835 2110);
DISPLAY 0.680851 (-1835 2110);
PAINT MONO (-1835 2110);
FORCEPROP 0 LASTPIN (-1825 2150) $PN 155
J 2
(-1835 2160);
DISPLAY 0.680851 (-1835 2160);
PAINT MONO (-1835 2160);
FORCEPROP 0 LASTPIN (-1825 2200) $PN 158
J 2
(-1835 2210);
DISPLAY 0.680851 (-1835 2210);
PAINT MONO (-1835 2210);
FORCEPROP 0 LASTPIN (-1825 2250) $PN 160
J 2
(-1835 2260);
DISPLAY 0.680851 (-1835 2260);
PAINT MONO (-1835 2260);
FORCEPROP 0 LASTPIN (-1825 2300) $PN 162
J 2
(-1835 2310);
DISPLAY 0.680851 (-1835 2310);
PAINT MONO (-1835 2310);
FORCEPROP 0 LASTPIN (-1825 2350) $PN 164
J 2
(-1835 2360);
DISPLAY 0.680851 (-1835 2360);
PAINT MONO (-1835 2360);
FORCEPROP 0 LASTPIN (-1825 2400) $PN 166
J 2
(-1835 2410);
DISPLAY 0.680851 (-1835 2410);
PAINT MONO (-1835 2410);
FORCEPROP 0 LASTPIN (-1825 2450) $PN 169
J 2
(-1835 2460);
DISPLAY 0.680851 (-1835 2460);
PAINT MONO (-1835 2460);
FORCEPROP 0 LASTPIN (-1825 2500) $PN 171
J 2
(-1835 2510);
DISPLAY 0.680851 (-1835 2510);
PAINT MONO (-1835 2510);
FORCEPROP 0 LASTPIN (-1825 2550) $PN 173
J 2
(-1835 2560);
DISPLAY 0.680851 (-1835 2560);
PAINT MONO (-1835 2560);
FORCEPROP 0 LASTPIN (-1825 2600) $PN 175
J 2
(-1835 2610);
DISPLAY 0.680851 (-1835 2610);
PAINT MONO (-1835 2610);
FORCEPROP 0 LASTPIN (-1825 2650) $PN 177
J 2
(-1835 2660);
DISPLAY 0.680851 (-1835 2660);
PAINT MONO (-1835 2660);
FORCEPROP 0 LASTPIN (-1825 2700) $PN 180
J 2
(-1835 2710);
DISPLAY 0.680851 (-1835 2710);
PAINT MONO (-1835 2710);
FORCEPROP 0 LASTPIN (-1825 2750) $PN 182
J 2
(-1835 2760);
DISPLAY 0.680851 (-1835 2760);
PAINT MONO (-1835 2760);
FORCEPROP 0 LASTPIN (-1825 2800) $PN 184
J 2
(-1835 2810);
DISPLAY 0.680851 (-1835 2810);
PAINT MONO (-1835 2810);
FORCEPROP 0 LASTPIN (-1825 2850) $PN 186
J 2
(-1835 2860);
DISPLAY 0.680851 (-1835 2860);
PAINT MONO (-1835 2860);
FORCEPROP 0 LASTPIN (-1825 2900) $PN 188
J 2
(-1835 2910);
DISPLAY 0.680851 (-1835 2910);
PAINT MONO (-1835 2910);
FORCEPROP 0 LASTPIN (-1825 2950) $PN 191
J 2
(-1835 2960);
DISPLAY 0.680851 (-1835 2960);
PAINT MONO (-1835 2960);
FORCEPROP 0 LASTPIN (-1825 3000) $PN 193
J 2
(-1835 3010);
DISPLAY 0.680851 (-1835 3010);
PAINT MONO (-1835 3010);
FORCEPROP 0 LASTPIN (-1825 3050) $PN 195
J 2
(-1835 3060);
DISPLAY 0.680851 (-1835 3060);
PAINT MONO (-1835 3060);
FORCEPROP 0 LASTPIN (-1825 3100) $PN 197
J 2
(-1835 3110);
DISPLAY 0.680851 (-1835 3110);
PAINT MONO (-1835 3110);
FORCEPROP 0 LASTPIN (-1825 3150) $PN 199
J 2
(-1835 3160);
DISPLAY 0.680851 (-1835 3160);
PAINT MONO (-1835 3160);
FORCEPROP 0 LASTPIN (-1825 3200) $PN 202
J 2
(-1835 3210);
DISPLAY 0.680851 (-1835 3210);
PAINT MONO (-1835 3210);
FORCEPROP 0 LASTPIN (-1825 3250) $PN 204
J 2
(-1835 3260);
DISPLAY 0.680851 (-1835 3260);
PAINT MONO (-1835 3260);
FORCEPROP 0 LASTPIN (-1825 3300) $PN 206
J 2
(-1835 3310);
DISPLAY 0.680851 (-1835 3310);
PAINT MONO (-1835 3310);
FORCEPROP 0 LASTPIN (-1825 3350) $PN 208
J 2
(-1835 3360);
DISPLAY 0.680851 (-1835 3360);
PAINT MONO (-1835 3360);
FORCEPROP 0 LASTPIN (-1825 3400) $PN 210
J 2
(-1835 3410);
DISPLAY 0.680851 (-1835 3410);
PAINT MONO (-1835 3410);
FORCEPROP 0 LASTPIN (-1825 3450) $PN 212
J 2
(-1835 3460);
DISPLAY 0.680851 (-1835 3460);
PAINT MONO (-1835 3460);
FORCEPROP 0 LASTPIN (-1825 3500) $PN 214
J 2
(-1835 3510);
DISPLAY 0.680851 (-1835 3510);
PAINT MONO (-1835 3510);
FORCEPROP 0 LASTPIN (-1825 3550) $PN 216
J 2
(-1835 3560);
DISPLAY 0.680851 (-1835 3560);
PAINT MONO (-1835 3560);
FORCEPROP 0 LASTPIN (-1825 3600) $PN 219
J 2
(-1835 3610);
DISPLAY 0.680851 (-1835 3610);
PAINT MONO (-1835 3610);
FORCEPROP 0 LASTPIN (-1825 3650) $PN 222
J 2
(-1835 3660);
DISPLAY 0.680851 (-1835 3660);
PAINT MONO (-1835 3660);
FORCEPROP 0 LASTPIN (-1825 3700) $PN 224
J 2
(-1835 3710);
DISPLAY 0.680851 (-1835 3710);
PAINT MONO (-1835 3710);
FORCEPROP 0 LASTPIN (-1825 3750) $PN 226
J 2
(-1835 3760);
DISPLAY 0.680851 (-1835 3760);
PAINT MONO (-1835 3760);
FORCEPROP 0 LASTPIN (-1825 3800) $PN 228
J 2
(-1835 3810);
DISPLAY 0.680851 (-1835 3810);
PAINT MONO (-1835 3810);
FORCEPROP 0 LASTPIN (-1825 3850) $PN 230
J 2
(-1835 3860);
DISPLAY 0.680851 (-1835 3860);
PAINT MONO (-1835 3860);
FORCEPROP 0 LASTPIN (-1825 3900) $PN 233
J 2
(-1835 3910);
DISPLAY 0.680851 (-1835 3910);
PAINT MONO (-1835 3910);
FORCEPROP 0 LASTPIN (-1825 3950) $PN 235
J 2
(-1835 3960);
DISPLAY 0.680851 (-1835 3960);
PAINT MONO (-1835 3960);
FORCEPROP 0 LASTPIN (-1825 4000) $PN 237
J 2
(-1835 4010);
DISPLAY 0.680851 (-1835 4010);
PAINT MONO (-1835 4010);
FORCEPROP 0 LASTPIN (-1825 4050) $PN 240
J 2
(-1835 4060);
DISPLAY 0.680851 (-1835 4060);
PAINT MONO (-1835 4060);
FORCEPROP 0 LASTPIN (-1825 4100) $PN 242
J 2
(-1835 4110);
DISPLAY 0.680851 (-1835 4110);
PAINT MONO (-1835 4110);
FORCEPROP 0 LASTPIN (-1825 4150) $PN 244
J 2
(-1835 4160);
DISPLAY 0.680851 (-1835 4160);
PAINT MONO (-1835 4160);
FORCEPROP 0 LASTPIN (-1825 4200) $PN 246
J 2
(-1835 4210);
DISPLAY 0.680851 (-1835 4210);
PAINT MONO (-1835 4210);
FORCEPROP 0 LASTPIN (-1825 4250) $PN 248
J 2
(-1835 4260);
DISPLAY 0.680851 (-1835 4260);
PAINT MONO (-1835 4260);
FORCEPROP 0 LASTPIN (-1825 4300) $PN 251
J 2
(-1835 4310);
DISPLAY 0.680851 (-1835 4310);
PAINT MONO (-1835 4310);
FORCEPROP 0 LASTPIN (-1825 4350) $PN 253
J 2
(-1835 4360);
DISPLAY 0.680851 (-1835 4360);
PAINT MONO (-1835 4360);
FORCEPROP 0 LASTPIN (-1825 4400) $PN 255
J 2
(-1835 4410);
DISPLAY 0.680851 (-1835 4410);
PAINT MONO (-1835 4410);
FORCEPROP 0 LASTPIN (-1825 4450) $PN 257
J 2
(-1835 4460);
DISPLAY 0.680851 (-1835 4460);
PAINT MONO (-1835 4460);
FORCEPROP 0 LASTPIN (-1825 4500) $PN 259
J 2
(-1835 4510);
DISPLAY 0.680851 (-1835 4510);
PAINT MONO (-1835 4510);
FORCEPROP 0 LASTPIN (-1825 4550) $PN 262
J 2
(-1835 4560);
DISPLAY 0.680851 (-1835 4560);
PAINT MONO (-1835 4560);
FORCEPROP 0 LASTPIN (-1825 4600) $PN 264
J 2
(-1835 4610);
DISPLAY 0.680851 (-1835 4610);
PAINT MONO (-1835 4610);
FORCEPROP 0 LASTPIN (-1825 4650) $PN 266
J 2
(-1835 4660);
DISPLAY 0.680851 (-1835 4660);
PAINT MONO (-1835 4660);
FORCEPROP 0 LASTPIN (-1825 4700) $PN 268
J 2
(-1835 4710);
DISPLAY 0.680851 (-1835 4710);
PAINT MONO (-1835 4710);
FORCEPROP 0 LASTPIN (-1825 4750) $PN 270
J 2
(-1835 4760);
DISPLAY 0.680851 (-1835 4760);
PAINT MONO (-1835 4760);
FORCEPROP 0 LASTPIN (-1825 4800) $PN 273
J 2
(-1835 4810);
DISPLAY 0.680851 (-1835 4810);
PAINT MONO (-1835 4810);
FORCEPROP 0 LASTPIN (-1825 4850) $PN 275
J 2
(-1835 4860);
DISPLAY 0.680851 (-1835 4860);
PAINT MONO (-1835 4860);
FORCEPROP 0 LASTPIN (-1825 4900) $PN 277
J 2
(-1835 4910);
DISPLAY 0.680851 (-1835 4910);
PAINT MONO (-1835 4910);
FORCEPROP 0 LASTPIN (-1825 4950) $PN 279
J 2
(-1835 4960);
DISPLAY 0.680851 (-1835 4960);
PAINT MONO (-1835 4960);
FORCEPROP 0 LASTPIN (-1825 5000) $PN 281
J 2
(-1835 5010);
DISPLAY 0.680851 (-1835 5010);
PAINT MONO (-1835 5010);
FORCEPROP 0 LASTPIN (-1825 5050) $PN 284
J 2
(-1835 5060);
DISPLAY 0.680851 (-1835 5060);
PAINT MONO (-1835 5060);
FORCEPROP 0 LASTPIN (-1825 5100) $PN 286
J 2
(-1835 5110);
DISPLAY 0.680851 (-1835 5110);
PAINT MONO (-1835 5110);
FORCEPROP 0 LASTPIN (-1825 5150) $PN 288
J 2
(-1835 5160);
DISPLAY 0.680851 (-1835 5160);
PAINT MONO (-1835 5160);
FORCEPROP 2 LAST PART_TYPE SMLF
J 0
(-1675 5725);
DISPLAY 1.021277 (-1675 5725);
FORCEPROP 1 LAST MATERIAL IO
J 0
(-1675 5475);
DISPLAY 0.468085 (-1675 5475);
PAINT SKYBLUE (-1675 5475);
FORCEPROP 2 LAST VALUE SCONN288_DDR506112002KQ
J 0
(-1675 5675);
DISPLAY 0.489362 (-1675 5675);
PAINT SKYBLUE (-1675 5675);
FORCEPROP 1 LAST PART_NUMBER DFHST8FS479
J 0
(-1675 5550);
DISPLAY 0.468085 (-1675 5550);
PAINT SKYBLUE (-1675 5550);
FORCEPROP 1 LAST CDS_LMAN_SYM_OUTLINE -450,1800,450,-1750
J 0
(-1225 3650);
DISPLAY 0.468085 (-1225 3650);
PAINT GREEN (-1225 3650);
DISPLAY INVISIBLE (-1225 3650);
FORCEPROP 1 LAST PATH I174
J 0
(-1225 3650);
DISPLAY 0.723404 (-1225 3650);
PAINT GREEN (-1225 3650);
DISPLAY INVISIBLE (-1225 3650);
FORCEPROP 1 LAST NEEDS_NO_SIZE TRUE
J 0
(-1225 3650);
DISPLAY 0.723404 (-1225 3650);
PAINT GREEN (-1225 3650);
DISPLAY INVISIBLE (-1225 3650);
FORCEPROP 2 LAST CDS_LIB pure_quanta
J 0
(-1225 3650);
DISPLAY INVISIBLE (-1225 3650);
FORCEADD OFFPAGE..6
(-8250 2850);
FORCEPROP 2 LAST $XR5 136 
J 0
(-9130 2850);
DISPLAY 0.638298 (-9130 2850);
PAINT MONO (-9130 2850);
FORCEPROP 2 LAST $XR4 108 
J 0
(-9010 2850);
DISPLAY 0.638298 (-9010 2850);
PAINT MONO (-9010 2850);
FORCEPROP 2 LAST $XR3 107 
J 0
(-8890 2850);
DISPLAY 0.638298 (-8890 2850);
PAINT MONO (-8890 2850);
FORCEPROP 2 LAST $XR2 106 
J 0
(-8770 2850);
DISPLAY 0.638298 (-8770 2850);
PAINT MONO (-8770 2850);
FORCEPROP 2 LAST $XR1 105 
J 0
(-8650 2850);
DISPLAY 0.638298 (-8650 2850);
PAINT MONO (-8650 2850);
FORCEPROP 2 LAST $XR0 103 
J 0
(-8530 2850);
DISPLAY 0.638298 (-8530 2850);
PAINT MONO (-8530 2850);
FORCEPROP 2 LAST PATH I179
J 0
(-8550 2900);
DISPLAY 1.021277 (-8550 2900);
DISPLAY INVISIBLE (-8550 2900);
FORCEPROP 1 LAST COMMENT_BODY TRUE
J 0
(-8150 2775);
DISPLAY 0.872340 (-8150 2775);
PAINT GREEN (-8150 2775);
DISPLAY INVISIBLE (-8150 2775);
FORCEPROP 1 LAST OFFPAGE TRUE
J 0
(-7925 2725);
DISPLAY 0.872340 (-7925 2725);
PAINT GREEN (-7925 2725);
DISPLAY INVISIBLE (-7925 2725);
FORCEPROP 2 LAST CDS_LIB mstr_standard
J 0
(-8250 2850);
DISPLAY 0.808511 (-8250 2850);
DISPLAY INVISIBLE (-8250 2850);
FORCEADD OFFPAGE..1
(-8250 4450);
FORCEPROP 2 LAST $XR0 44 
J 0
(-8501 4450);
DISPLAY 0.638298 (-8501 4450);
PAINT MONO (-8501 4450);
FORCEPROP 2 LAST PATH I18
J 0
(-8450 4500);
DISPLAY 1.021277 (-8450 4500);
DISPLAY INVISIBLE (-8450 4500);
FORCEPROP 1 LAST COMMENT_BODY TRUE
J 0
(-8125 4350);
DISPLAY 0.872340 (-8125 4350);
PAINT GREEN (-8125 4350);
DISPLAY INVISIBLE (-8125 4350);
FORCEPROP 1 LAST OFFPAGE TRUE
J 0
(-7925 4325);
DISPLAY 0.872340 (-7925 4325);
PAINT GREEN (-7925 4325);
DISPLAY INVISIBLE (-7925 4325);
FORCEPROP 2 LAST CDS_LIB mstr_standard
J 0
(-8250 4450);
DISPLAY 0.723404 (-8250 4450);
PAINT MONO (-8250 4450);
DISPLAY INVISIBLE (-8250 4450);
FORCEADD Q_CAP..1
R 2
(-8575 3225);
FORCEPROP 1 LAST LOCATION C164
J 2
(-8625 3325);
DISPLAY 0.489362 (-8625 3325);
PAINT SKYBLUE (-8625 3325);
FORCEPROP 0 LAST $SEC 1
J 0
(-8625 3375);
DISPLAY 0.680851 (-8625 3375);
PAINT MONO (-8625 3375);
DISPLAY INVISIBLE (-8625 3375);
FORCEPROP 0 LAST CDS_SEC 1
J 0
(-8625 3375);
DISPLAY 1.021277 (-8625 3375);
DISPLAY INVISIBLE (-8625 3375);
FORCEPROP 1 LASTPIN (-8575 3325) $PN 1
J 2
(-8585 3305);
DISPLAY 0.489362 (-8585 3305);
PAINT MONO (-8585 3305);
FORCEPROP 1 LASTPIN (-8575 3125) $PN 2
J 2
(-8585 3105);
DISPLAY 0.489362 (-8585 3105);
PAINT MONO (-8585 3105);
FORCEPROP 1 LAST MATERIAL X7R
J 2
(-8625 3125);
DISPLAY 0.489362 (-8625 3125);
PAINT SKYBLUE (-8625 3125);
FORCEPROP 1 LAST TOLERANCE 10%
J 2
(-8625 3175);
DISPLAY 0.489362 (-8625 3175);
PAINT SKYBLUE (-8625 3175);
FORCEPROP 1 LAST VALUE 0.1UF
J 2
(-8625 3275);
DISPLAY 0.489362 (-8625 3275);
PAINT SKYBLUE (-8625 3275);
FORCEPROP 1 LAST PART_NUMBER CH4104K1B00
J 2
(-8625 3075);
DISPLAY 0.489362 (-8625 3075);
PAINT SKYBLUE (-8625 3075);
FORCEPROP 1 LAST VOLTAGE 25V
J 2
(-8625 3225);
DISPLAY 0.489362 (-8625 3225);
PAINT SKYBLUE (-8625 3225);
FORCEPROP 1 LAST PACK_TYPE 0402
J 2
(-8625 3025);
DISPLAY 0.489362 (-8625 3025);
PAINT SKYBLUE (-8625 3025);
FORCEPROP 0 LAST BOM_COST MEM
J 2
(-8630 3370);
DISPLAY 0.595745 (-8630 3370);
PAINT MONO (-8630 3370);
DISPLAY INVISIBLE (-8630 3370);
FORCEPROP 2 LAST CDS_LIB pure_quanta
J 0
(-8575 3225);
DISPLAY INVISIBLE (-8575 3225);
FORCEPROP 1 LAST PATH I185
J 2
(-8625 3375);
DISPLAY 0.978723 (-8625 3375);
PAINT WHITE (-8625 3375);
DISPLAY INVISIBLE (-8625 3375);
FORCEPROP 0 LAST ROOM MEM_CH_A_CPU0_DIMM1
J 2
(-8630 3370);
DISPLAY 0.595745 (-8630 3370);
PAINT RED (-8630 3370);
DISPLAY INVISIBLE (-8630 3370);
FORCEADD GND..1
(-8575 3000);
FORCEPROP 3 LASTPIN (-8575 3050) SIG_NAME GND\g
J 0
(-8565 3060);
DISPLAY 0.659574 (-8565 3060);
PAINT MONO (-8565 3060);
DISPLAY INVISIBLE (-8565 3060);
FORCEPROP 2 LAST BOM_COST MEM
J 0
(-8550 3125);
DISPLAY 0.659574 (-8550 3125);
DISPLAY INVISIBLE (-8550 3125);
FORCEPROP 1 LAST SIZE 1B
J 0
(-8500 2950);
DISPLAY 0.723404 (-8500 2950);
PAINT GREEN (-8500 2950);
DISPLAY INVISIBLE (-8500 2950);
FORCEPROP 2 LAST CDS_LIB mstr_symbols
J 0
(-8575 3000);
DISPLAY 0.808511 (-8575 3000);
DISPLAY INVISIBLE (-8575 3000);
FORCEPROP 1 LAST BODY_TYPE PLUMBING
J 0
(-8620 2957);
DISPLAY 0.276596 (-8620 2957);
PAINT GREEN (-8620 2957);
DISPLAY INVISIBLE (-8620 2957);
FORCEPROP 1 LAST PATH I186
J 0
(-8500 3000);
DISPLAY 0.872340 (-8500 3000);
PAINT AQUA (-8500 3000);
DISPLAY INVISIBLE (-8500 3000);
FORCEPROP 1 LAST VOLTAGE 0
J 0
(-8595 3095);
DISPLAY 0.829787 (-8595 3095);
PAINT SKYBLUE (-8595 3095);
DISPLAY INVISIBLE (-8595 3095);
FORCEPROP 2 LAST ROOM MEM_EFGH_DECOUPLING_CAPS
J 0
(-8550 3075);
DISPLAY 0.659574 (-8550 3075);
PAINT RED (-8550 3075);
DISPLAY INVISIBLE (-8550 3075);
FORCEPROP 1 LAST HDL_POWER GND
J 0
(-8575 3150);
DISPLAY 0.723404 (-8575 3150);
PAINT GREEN (-8575 3150);
DISPLAY INVISIBLE (-8575 3150);
FORCEADD OFFPAGE..6
(-9025 2150);
FORCEPROP 2 LAST $XR5 81 
J 0
(-9305 2042);
DISPLAY 0.638298 (-9305 2042);
PAINT MONO (-9305 2042);
FORCEPROP 2 LAST $XR4 108 
J 0
(-9305 2222);
DISPLAY 0.638298 (-9305 2222);
PAINT MONO (-9305 2222);
FORCEPROP 2 LAST $XR3 107 
J 0
(-9305 2078);
DISPLAY 0.638298 (-9305 2078);
PAINT MONO (-9305 2078);
FORCEPROP 2 LAST $XR2 106 
J 0
(-9305 2186);
DISPLAY 0.638298 (-9305 2186);
PAINT MONO (-9305 2186);
FORCEPROP 2 LAST $XR1 105 
J 0
(-9305 2114);
DISPLAY 0.638298 (-9305 2114);
PAINT MONO (-9305 2114);
FORCEPROP 2 LAST $XR0 103 
J 0
(-9305 2150);
DISPLAY 0.638298 (-9305 2150);
PAINT MONO (-9305 2150);
FORCEPROP 2 LAST PATH I187
J 0
(-8975 2225);
DISPLAY 1.021277 (-8975 2225);
DISPLAY INVISIBLE (-8975 2225);
FORCEPROP 1 LAST COMMENT_BODY TRUE
J 0
(-8925 2075);
DISPLAY 0.872340 (-8925 2075);
PAINT GREEN (-8925 2075);
DISPLAY INVISIBLE (-8925 2075);
FORCEPROP 1 LAST OFFPAGE TRUE
J 0
(-8700 2025);
DISPLAY 0.872340 (-8700 2025);
PAINT GREEN (-8700 2025);
DISPLAY INVISIBLE (-8700 2025);
FORCEPROP 2 LAST CDS_LIB mstr_standard
J 0
(-9025 2150);
DISPLAY INVISIBLE (-9025 2150);
FORCEADD Q_RES..1
R 2
(-8475 2150);
FORCEPROP 1 LAST LOCATION R310
J 2
(-8425 2200);
DISPLAY 0.489362 (-8425 2200);
PAINT SKYBLUE (-8425 2200);
FORCEPROP 0 LAST $SEC 1
J 0
(-8425 2250);
DISPLAY 0.680851 (-8425 2250);
PAINT MONO (-8425 2250);
DISPLAY INVISIBLE (-8425 2250);
FORCEPROP 0 LAST CDS_SEC 1
J 0
(-8425 2250);
DISPLAY 1.021277 (-8425 2250);
DISPLAY INVISIBLE (-8425 2250);
FORCEPROP 1 LASTPIN (-8375 2150) $PN 1
J 2
(-8387 2162);
DISPLAY 0.489362 (-8387 2162);
PAINT MONO (-8387 2162);
FORCEPROP 1 LASTPIN (-8575 2150) $PN 2
J 2
(-8537 2162);
DISPLAY 0.489362 (-8537 2162);
PAINT MONO (-8537 2162);
FORCEPROP 1 LAST VALUE 0
J 0
(-8475 2100);
DISPLAY 0.489362 (-8475 2100);
PAINT SKYBLUE (-8475 2100);
FORCEPROP 2 LAST BOM_COST MEM
J 0
(-8500 2300);
DISPLAY 0.744681 (-8500 2300);
PAINT WHITE (-8500 2300);
DISPLAY INVISIBLE (-8500 2300);
FORCEPROP 2 LAST CDS_LIB pure_quanta
J 0
(-8475 2150);
DISPLAY INVISIBLE (-8475 2150);
FORCEPROP 1 LAST PATH I189
J 2
(-8425 2300);
DISPLAY 0.978723 (-8425 2300);
PAINT WHITE (-8425 2300);
DISPLAY INVISIBLE (-8425 2300);
FORCEPROP 1 LAST WATTAGE 1/16W
J 0
(-8400 2075);
DISPLAY 0.489362 (-8400 2075);
PAINT SKYBLUE (-8400 2075);
DISPLAY INVISIBLE (-8400 2075);
FORCEPROP 1 LAST MATERIAL CHIP
J 0
(-8650 2125);
DISPLAY 0.489362 (-8650 2125);
PAINT SKYBLUE (-8650 2125);
DISPLAY INVISIBLE (-8650 2125);
FORCEPROP 1 LAST TOLERANCE 5%
J 2
(-8350 2125);
DISPLAY 0.489362 (-8350 2125);
PAINT SKYBLUE (-8350 2125);
DISPLAY INVISIBLE (-8350 2125);
FORCEPROP 1 LAST PART_NUMBER CS00002JB38
J 0
(-8575 2200);
DISPLAY 0.489362 (-8575 2200);
PAINT SKYBLUE (-8575 2200);
DISPLAY INVISIBLE (-8575 2200);
FORCEPROP 1 LAST PACK_TYPE 0402LF
J 0
(-8650 2075);
DISPLAY 0.489362 (-8650 2075);
PAINT SKYBLUE (-8650 2075);
DISPLAY INVISIBLE (-8650 2075);
FORCEPROP 2 LAST ROOM RST_CPU0_PLD_TO_DIMM
J 0
(-8500 2250);
DISPLAY 0.744681 (-8500 2250);
PAINT RED (-8500 2250);
DISPLAY INVISIBLE (-8500 2250);
FORCEADD OFFPAGE..1
(-8250 4600);
FORCEPROP 2 LAST $XR0 44 
J 0
(-8501 4600);
DISPLAY 0.638298 (-8501 4600);
PAINT MONO (-8501 4600);
FORCEPROP 2 LAST PATH I19
J 0
(-8450 4650);
DISPLAY 1.021277 (-8450 4650);
DISPLAY INVISIBLE (-8450 4650);
FORCEPROP 1 LAST COMMENT_BODY TRUE
J 0
(-8125 4500);
DISPLAY 0.872340 (-8125 4500);
PAINT GREEN (-8125 4500);
DISPLAY INVISIBLE (-8125 4500);
FORCEPROP 1 LAST OFFPAGE TRUE
J 0
(-7925 4475);
DISPLAY 0.872340 (-7925 4475);
PAINT GREEN (-7925 4475);
DISPLAY INVISIBLE (-7925 4475);
FORCEPROP 2 LAST CDS_LIB mstr_standard
J 0
(-8250 4600);
DISPLAY 0.723404 (-8250 4600);
PAINT MONO (-8250 4600);
DISPLAY INVISIBLE (-8250 4600);
FORCEADD Q_RES..2
(-8350 2300);
FORCEPROP 1 LAST LOCATION R111
J 0
(-8305 2425);
DISPLAY 0.489362 (-8305 2425);
PAINT SKYBLUE (-8305 2425);
FORCEPROP 0 LAST $SEC 1
J 0
(-8300 2475);
DISPLAY 0.680851 (-8300 2475);
PAINT MONO (-8300 2475);
DISPLAY INVISIBLE (-8300 2475);
FORCEPROP 0 LAST CDS_SEC 1
J 0
(-8300 2475);
DISPLAY 1.021277 (-8300 2475);
DISPLAY INVISIBLE (-8300 2475);
FORCEPROP 1 LASTPIN (-8350 2400) $PN 1
J 0
(-8345 2362);
DISPLAY 0.489362 (-8345 2362);
PAINT MONO (-8345 2362);
FORCEPROP 1 LASTPIN (-8350 2200) $PN 2
J 0
(-8345 2210);
DISPLAY 0.489362 (-8345 2210);
PAINT MONO (-8345 2210);
FORCEPROP 1 LAST WATTAGE 1/16W
J 0
(-8300 2325);
DISPLAY 0.489362 (-8300 2325);
PAINT SKYBLUE (-8300 2325);
FORCEPROP 1 LAST MATERIAL EMPTY
J 0
(-8300 2300);
DISPLAY 0.489362 (-8300 2300);
PAINT RED (-8300 2300);
FORCEPROP 1 LAST TOLERANCE 5%
J 0
(-8300 2350);
DISPLAY 0.489362 (-8300 2350);
PAINT SKYBLUE (-8300 2350);
FORCEPROP 1 LAST VALUE 1K
J 0
(-8305 2375);
DISPLAY 0.489362 (-8305 2375);
PAINT SKYBLUE (-8305 2375);
FORCEPROP 1 LAST PACK_TYPE 0402LF
J 0
(-8300 2250);
DISPLAY 0.489362 (-8300 2250);
PAINT SKYBLUE (-8300 2250);
FORCEPROP 2 LAST BOM_COST MEM
J 0
(-8300 2475);
DISPLAY 0.808511 (-8300 2475);
DISPLAY INVISIBLE (-8300 2475);
FORCEPROP 2 LAST CDS_LIB pure_quanta
J 0
(-8350 2300);
DISPLAY INVISIBLE (-8350 2300);
FORCEPROP 1 LAST PATH I190
J 0
(-8300 2475);
DISPLAY 0.978723 (-8300 2475);
PAINT WHITE (-8300 2475);
DISPLAY INVISIBLE (-8300 2475);
FORCEPROP 1 LAST PART_NUMBER TMP_QCS21002JB34
J 0
(-8300 2275);
DISPLAY 0.489362 (-8300 2275);
PAINT SKYBLUE (-8300 2275);
DISPLAY INVISIBLE (-8300 2275);
FORCEPROP 2 LAST ROOM MEM_CH_A_CPU0_DIMM1
J 0
(-8300 2525);
DISPLAY 0.808511 (-8300 2525);
PAINT RED (-8300 2525);
DISPLAY INVISIBLE (-8300 2525);
FORCEADD VCC_CORE..1
(-8350 2475);
FORCEPROP 3 LASTPIN (-8350 2425) SIG_NAME P3V3_STBY\g
J 0
(-8340 2435);
DISPLAY 0.659574 (-8340 2435);
PAINT MONO (-8340 2435);
DISPLAY INVISIBLE (-8340 2435);
FORCEPROP 1 LAST HDL_POWER P3V3_STBY
J 1
(-8350 2525);
DISPLAY 0.489362 (-8350 2525);
PAINT GREEN (-8350 2525);
FORCEPROP 2 LAST CDS_LIB mstr_symbols
J 0
(-8350 2475);
DISPLAY INVISIBLE (-8350 2475);
FORCEPROP 1 LAST PATH I192
J 0
(-8300 2500);
DISPLAY 0.872340 (-8300 2500);
PAINT AQUA (-8300 2500);
DISPLAY INVISIBLE (-8300 2500);
FORCEPROP 0 LAST VOLTAGE 3.3
J 0
(-8625 2625);
DISPLAY 1.021277 (-8625 2625);
PAINT SKYBLUE (-8625 2625);
DISPLAY INVISIBLE (-8625 2625);
FORCEPROP 2 LAST ROOM PVCCINFAON_CPU0_CTRL
J 0
(-8350 2575);
DISPLAY 0.808511 (-8350 2575);
PAINT RED (-8350 2575);
DISPLAY INVISIBLE (-8350 2575);
FORCEADD TAP..1
(-3225 3675);
FORCEPROP 3 LASTPIN (-3275 3675) SIG_NAME M_H_CPU1_SA_DQS_DN<2>
J 0
(-3265 3685);
DISPLAY 0.659574 (-3265 3685);
PAINT MONO (-3265 3685);
DISPLAY INVISIBLE (-3265 3685);
FORCEPROP 1 LASTPIN (-3275 3675) BN 2
J 0
(-3287 3683);
DISPLAY 0.489362 (-3287 3683);
PAINT GREEN (-3287 3683);
FORCEPROP 2 LAST CDS_LIB mstr_standard
J 0
(-3225 3675);
DISPLAY 0.723404 (-3225 3675);
PAINT MONO (-3225 3675);
DISPLAY INVISIBLE (-3225 3675);
FORCEPROP 1 LAST BODY_TYPE PLUMBING
J 0
(-3225 3725);
DISPLAY 0.872340 (-3225 3725);
PAINT GREEN (-3225 3725);
DISPLAY INVISIBLE (-3225 3725);
FORCEPROP 1 LAST HDL_TAP TRUE
J 0
(-2900 3550);
DISPLAY 0.872340 (-2900 3550);
DISPLAY INVISIBLE (-2900 3550);
FORCEPROP 1 LAST PATH I193
J 0
(-3227 3675);
DISPLAY 0.872340 (-3227 3675);
PAINT GREEN (-3227 3675);
DISPLAY INVISIBLE (-3227 3675);
FORCEADD TAP..1
(-3225 3775);
FORCEPROP 3 LASTPIN (-3275 3775) SIG_NAME M_H_CPU1_SA_DQS_DN<3>
J 0
(-3265 3785);
DISPLAY 0.659574 (-3265 3785);
PAINT MONO (-3265 3785);
DISPLAY INVISIBLE (-3265 3785);
FORCEPROP 1 LASTPIN (-3275 3775) BN 3
J 0
(-3287 3783);
DISPLAY 0.489362 (-3287 3783);
PAINT GREEN (-3287 3783);
FORCEPROP 2 LAST CDS_LIB mstr_standard
J 0
(-3225 3775);
DISPLAY 0.723404 (-3225 3775);
PAINT MONO (-3225 3775);
DISPLAY INVISIBLE (-3225 3775);
FORCEPROP 1 LAST BODY_TYPE PLUMBING
J 0
(-3225 3825);
DISPLAY 0.872340 (-3225 3825);
PAINT GREEN (-3225 3825);
DISPLAY INVISIBLE (-3225 3825);
FORCEPROP 1 LAST HDL_TAP TRUE
J 0
(-2900 3650);
DISPLAY 0.872340 (-2900 3650);
DISPLAY INVISIBLE (-2900 3650);
FORCEPROP 1 LAST PATH I194
J 0
(-3227 3775);
DISPLAY 0.872340 (-3227 3775);
PAINT GREEN (-3227 3775);
DISPLAY INVISIBLE (-3227 3775);
FORCEADD TAP..1
(-3425 3925);
FORCEPROP 3 LASTPIN (-3475 3925) SIG_NAME M_H_CPU1_SA_DQS_DP<4>
J 0
(-3465 3935);
DISPLAY 0.659574 (-3465 3935);
PAINT MONO (-3465 3935);
DISPLAY INVISIBLE (-3465 3935);
FORCEPROP 1 LASTPIN (-3475 3925) BN 4
J 0
(-3487 3933);
DISPLAY 0.489362 (-3487 3933);
PAINT GREEN (-3487 3933);
FORCEPROP 2 LAST CDS_LIB mstr_standard
J 0
(-3425 3925);
DISPLAY 0.723404 (-3425 3925);
PAINT MONO (-3425 3925);
DISPLAY INVISIBLE (-3425 3925);
FORCEPROP 1 LAST BODY_TYPE PLUMBING
J 0
(-3425 3975);
DISPLAY 0.872340 (-3425 3975);
PAINT GREEN (-3425 3975);
DISPLAY INVISIBLE (-3425 3975);
FORCEPROP 1 LAST HDL_TAP TRUE
J 0
(-3100 3800);
DISPLAY 0.872340 (-3100 3800);
DISPLAY INVISIBLE (-3100 3800);
FORCEPROP 1 LAST PATH I195
J 0
(-3427 3925);
DISPLAY 0.872340 (-3427 3925);
PAINT GREEN (-3427 3925);
DISPLAY INVISIBLE (-3427 3925);
FORCEADD TAP..1
(-3425 4025);
FORCEPROP 3 LASTPIN (-3475 4025) SIG_NAME M_H_CPU1_SA_DQS_DP<5>
J 0
(-3465 4035);
DISPLAY 0.659574 (-3465 4035);
PAINT MONO (-3465 4035);
DISPLAY INVISIBLE (-3465 4035);
FORCEPROP 1 LASTPIN (-3475 4025) BN 5
J 0
(-3487 4033);
DISPLAY 0.489362 (-3487 4033);
PAINT GREEN (-3487 4033);
FORCEPROP 2 LAST CDS_LIB mstr_standard
J 0
(-3425 4025);
DISPLAY 0.723404 (-3425 4025);
PAINT MONO (-3425 4025);
DISPLAY INVISIBLE (-3425 4025);
FORCEPROP 1 LAST BODY_TYPE PLUMBING
J 0
(-3425 4075);
DISPLAY 0.872340 (-3425 4075);
PAINT GREEN (-3425 4075);
DISPLAY INVISIBLE (-3425 4075);
FORCEPROP 1 LAST HDL_TAP TRUE
J 0
(-3100 3900);
DISPLAY 0.872340 (-3100 3900);
DISPLAY INVISIBLE (-3100 3900);
FORCEPROP 1 LAST PATH I196
J 0
(-3427 4025);
DISPLAY 0.872340 (-3427 4025);
PAINT GREEN (-3427 4025);
DISPLAY INVISIBLE (-3427 4025);
FORCEADD OFFPAGE..2
(-2425 4475);
FORCEPROP 2 LAST $XR0 44 
J 0
(-2236 4475);
DISPLAY 0.638298 (-2236 4475);
PAINT MONO (-2236 4475);
FORCEPROP 1 LAST COMMENT_BODY TRUE
J 0
(-2470 4380);
DISPLAY 0.872340 (-2470 4380);
PAINT GREEN (-2470 4380);
DISPLAY INVISIBLE (-2470 4380);
FORCEPROP 1 LAST OFFPAGE TRUE
J 0
(-2100 4350);
DISPLAY 0.723404 (-2100 4350);
PAINT GREEN (-2100 4350);
DISPLAY INVISIBLE (-2100 4350);
FORCEPROP 2 LAST CDS_LIB mstr_standard
J 0
(-2425 4475);
DISPLAY 0.723404 (-2425 4475);
PAINT MONO (-2425 4475);
DISPLAY INVISIBLE (-2425 4475);
FORCEPROP 2 LAST PATH I198
J 0
(-2225 4525);
DISPLAY 0.680851 (-2225 4525);
DISPLAY INVISIBLE (-2225 4525);
FORCEADD OFFPAGE..2
(-2425 4425);
FORCEPROP 2 LAST $XR0 44 
J 0
(-2236 4425);
DISPLAY 0.638298 (-2236 4425);
PAINT MONO (-2236 4425);
FORCEPROP 1 LAST COMMENT_BODY TRUE
J 0
(-2470 4330);
DISPLAY 0.872340 (-2470 4330);
PAINT GREEN (-2470 4330);
DISPLAY INVISIBLE (-2470 4330);
FORCEPROP 1 LAST OFFPAGE TRUE
J 0
(-2100 4300);
DISPLAY 0.723404 (-2100 4300);
PAINT GREEN (-2100 4300);
DISPLAY INVISIBLE (-2100 4300);
FORCEPROP 2 LAST CDS_LIB mstr_standard
J 0
(-2425 4425);
DISPLAY 0.723404 (-2425 4425);
PAINT MONO (-2425 4425);
DISPLAY INVISIBLE (-2425 4425);
FORCEPROP 2 LAST PATH I199
J 0
(-2225 4475);
DISPLAY 0.680851 (-2225 4475);
DISPLAY INVISIBLE (-2225 4475);
FORCEADD OFFPAGE..5
(-8250 1950);
FORCEPROP 2 LAST $XR0 44 
J 0
(-8474 1950);
DISPLAY 0.638298 (-8474 1950);
PAINT MONO (-8474 1950);
FORCEPROP 2 LAST PATH I2
J 0
(-8500 2000);
DISPLAY 1.021277 (-8500 2000);
DISPLAY INVISIBLE (-8500 2000);
FORCEPROP 1 LAST COMMENT_BODY TRUE
J 0
(-8150 1875);
DISPLAY 0.872340 (-8150 1875);
PAINT GREEN (-8150 1875);
DISPLAY INVISIBLE (-8150 1875);
FORCEPROP 1 LAST OFFPAGE TRUE
J 0
(-7925 1825);
DISPLAY 0.872340 (-7925 1825);
PAINT GREEN (-7925 1825);
DISPLAY INVISIBLE (-7925 1825);
FORCEPROP 2 LAST CDS_LIB mstr_standard
J 0
(-8250 1950);
DISPLAY 0.808511 (-8250 1950);
DISPLAY INVISIBLE (-8250 1950);
FORCEADD OFFPAGE..1
(-8250 5050);
FORCEPROP 2 LAST $XR0 44 
J 0
(-8501 5050);
DISPLAY 0.638298 (-8501 5050);
PAINT MONO (-8501 5050);
FORCEPROP 2 LAST PATH I20
J 0
(-8450 5100);
DISPLAY 1.021277 (-8450 5100);
DISPLAY INVISIBLE (-8450 5100);
FORCEPROP 1 LAST COMMENT_BODY TRUE
J 0
(-8125 4950);
DISPLAY 0.872340 (-8125 4950);
PAINT GREEN (-8125 4950);
DISPLAY INVISIBLE (-8125 4950);
FORCEPROP 1 LAST OFFPAGE TRUE
J 0
(-7925 4925);
DISPLAY 0.872340 (-7925 4925);
PAINT GREEN (-7925 4925);
DISPLAY INVISIBLE (-7925 4925);
FORCEPROP 2 LAST CDS_LIB mstr_standard
J 0
(-8250 5050);
DISPLAY 0.723404 (-8250 5050);
PAINT MONO (-8250 5050);
DISPLAY INVISIBLE (-8250 5050);
FORCEADD OFFPAGE..2
(-2425 3425);
FORCEPROP 2 LAST $XR0 44 
J 0
(-2236 3425);
DISPLAY 0.638298 (-2236 3425);
PAINT MONO (-2236 3425);
FORCEPROP 1 LAST COMMENT_BODY TRUE
J 0
(-2470 3330);
DISPLAY 0.872340 (-2470 3330);
PAINT GREEN (-2470 3330);
DISPLAY INVISIBLE (-2470 3330);
FORCEPROP 1 LAST OFFPAGE TRUE
J 0
(-2100 3300);
DISPLAY 0.723404 (-2100 3300);
PAINT GREEN (-2100 3300);
DISPLAY INVISIBLE (-2100 3300);
FORCEPROP 2 LAST CDS_LIB mstr_standard
J 0
(-2425 3425);
DISPLAY 0.723404 (-2425 3425);
PAINT MONO (-2425 3425);
DISPLAY INVISIBLE (-2425 3425);
FORCEPROP 2 LAST PATH I200
J 0
(-2225 3475);
DISPLAY 0.680851 (-2225 3475);
DISPLAY INVISIBLE (-2225 3475);
FORCEADD OFFPAGE..2
(-2425 3375);
FORCEPROP 2 LAST $XR0 44 
J 0
(-2236 3375);
DISPLAY 0.638298 (-2236 3375);
PAINT MONO (-2236 3375);
FORCEPROP 1 LAST COMMENT_BODY TRUE
J 0
(-2470 3280);
DISPLAY 0.872340 (-2470 3280);
PAINT GREEN (-2470 3280);
DISPLAY INVISIBLE (-2470 3280);
FORCEPROP 1 LAST OFFPAGE TRUE
J 0
(-2100 3250);
DISPLAY 0.723404 (-2100 3250);
PAINT GREEN (-2100 3250);
DISPLAY INVISIBLE (-2100 3250);
FORCEPROP 2 LAST CDS_LIB mstr_standard
J 0
(-2425 3375);
DISPLAY 0.723404 (-2425 3375);
PAINT MONO (-2425 3375);
DISPLAY INVISIBLE (-2425 3375);
FORCEPROP 2 LAST PATH I201
J 0
(-2225 3425);
DISPLAY 0.680851 (-2225 3425);
DISPLAY INVISIBLE (-2225 3425);
FORCEADD TAP..1
(-3225 4375);
FORCEPROP 3 LASTPIN (-3275 4375) SIG_NAME M_H_CPU1_SA_DQS_DN<9>
J 0
(-3265 4385);
DISPLAY 0.659574 (-3265 4385);
PAINT MONO (-3265 4385);
DISPLAY INVISIBLE (-3265 4385);
FORCEPROP 1 LASTPIN (-3275 4375) BN 9
J 0
(-3287 4383);
DISPLAY 0.489362 (-3287 4383);
PAINT GREEN (-3287 4383);
FORCEPROP 2 LAST CDS_LIB mstr_standard
J 0
(-3225 4375);
DISPLAY 0.723404 (-3225 4375);
PAINT MONO (-3225 4375);
DISPLAY INVISIBLE (-3225 4375);
FORCEPROP 1 LAST BODY_TYPE PLUMBING
J 0
(-3225 4425);
DISPLAY 0.872340 (-3225 4425);
PAINT GREEN (-3225 4425);
DISPLAY INVISIBLE (-3225 4425);
FORCEPROP 1 LAST HDL_TAP TRUE
J 0
(-2900 4250);
DISPLAY 0.872340 (-2900 4250);
DISPLAY INVISIBLE (-2900 4250);
FORCEPROP 1 LAST PATH I202
J 0
(-3227 4375);
DISPLAY 0.872340 (-3227 4375);
PAINT GREEN (-3227 4375);
DISPLAY INVISIBLE (-3227 4375);
FORCEADD TAP..1
(-3225 4275);
FORCEPROP 3 LASTPIN (-3275 4275) SIG_NAME M_H_CPU1_SA_DQS_DN<8>
J 0
(-3265 4285);
DISPLAY 0.659574 (-3265 4285);
PAINT MONO (-3265 4285);
DISPLAY INVISIBLE (-3265 4285);
FORCEPROP 1 LASTPIN (-3275 4275) BN 8
J 0
(-3287 4283);
DISPLAY 0.489362 (-3287 4283);
PAINT GREEN (-3287 4283);
FORCEPROP 2 LAST CDS_LIB mstr_standard
J 0
(-3225 4275);
DISPLAY 0.723404 (-3225 4275);
PAINT MONO (-3225 4275);
DISPLAY INVISIBLE (-3225 4275);
FORCEPROP 1 LAST BODY_TYPE PLUMBING
J 0
(-3225 4325);
DISPLAY 0.872340 (-3225 4325);
PAINT GREEN (-3225 4325);
DISPLAY INVISIBLE (-3225 4325);
FORCEPROP 1 LAST HDL_TAP TRUE
J 0
(-2900 4150);
DISPLAY 0.872340 (-2900 4150);
DISPLAY INVISIBLE (-2900 4150);
FORCEPROP 1 LAST PATH I203
J 0
(-3227 4275);
DISPLAY 0.872340 (-3227 4275);
PAINT GREEN (-3227 4275);
DISPLAY INVISIBLE (-3227 4275);
FORCEADD TAP..1
(-3425 4425);
FORCEPROP 3 LASTPIN (-3475 4425) SIG_NAME M_H_CPU1_SA_DQS_DP<9>
J 0
(-3465 4435);
DISPLAY 0.659574 (-3465 4435);
PAINT MONO (-3465 4435);
DISPLAY INVISIBLE (-3465 4435);
FORCEPROP 1 LASTPIN (-3475 4425) BN 9
J 0
(-3487 4433);
DISPLAY 0.489362 (-3487 4433);
PAINT GREEN (-3487 4433);
FORCEPROP 2 LAST CDS_LIB mstr_standard
J 0
(-3425 4425);
DISPLAY 0.723404 (-3425 4425);
PAINT MONO (-3425 4425);
DISPLAY INVISIBLE (-3425 4425);
FORCEPROP 1 LAST BODY_TYPE PLUMBING
J 0
(-3425 4475);
DISPLAY 0.872340 (-3425 4475);
PAINT GREEN (-3425 4475);
DISPLAY INVISIBLE (-3425 4475);
FORCEPROP 1 LAST HDL_TAP TRUE
J 0
(-3100 4300);
DISPLAY 0.872340 (-3100 4300);
DISPLAY INVISIBLE (-3100 4300);
FORCEPROP 1 LAST PATH I204
J 0
(-3427 4425);
DISPLAY 0.872340 (-3427 4425);
PAINT GREEN (-3427 4425);
DISPLAY INVISIBLE (-3427 4425);
FORCEADD TAP..1
(-3425 4325);
FORCEPROP 3 LASTPIN (-3475 4325) SIG_NAME M_H_CPU1_SA_DQS_DP<8>
J 0
(-3465 4335);
DISPLAY 0.659574 (-3465 4335);
PAINT MONO (-3465 4335);
DISPLAY INVISIBLE (-3465 4335);
FORCEPROP 1 LASTPIN (-3475 4325) BN 8
J 0
(-3487 4333);
DISPLAY 0.489362 (-3487 4333);
PAINT GREEN (-3487 4333);
FORCEPROP 2 LAST CDS_LIB mstr_standard
J 0
(-3425 4325);
DISPLAY 0.723404 (-3425 4325);
PAINT MONO (-3425 4325);
DISPLAY INVISIBLE (-3425 4325);
FORCEPROP 1 LAST BODY_TYPE PLUMBING
J 0
(-3425 4375);
DISPLAY 0.872340 (-3425 4375);
PAINT GREEN (-3425 4375);
DISPLAY INVISIBLE (-3425 4375);
FORCEPROP 1 LAST HDL_TAP TRUE
J 0
(-3100 4200);
DISPLAY 0.872340 (-3100 4200);
DISPLAY INVISIBLE (-3100 4200);
FORCEPROP 1 LAST PATH I205
J 0
(-3427 4325);
DISPLAY 0.872340 (-3427 4325);
PAINT GREEN (-3427 4325);
DISPLAY INVISIBLE (-3427 4325);
FORCEADD TAP..1
(-3225 4175);
FORCEPROP 3 LASTPIN (-3275 4175) SIG_NAME M_H_CPU1_SA_DQS_DN<7>
J 0
(-3265 4185);
DISPLAY 0.659574 (-3265 4185);
PAINT MONO (-3265 4185);
DISPLAY INVISIBLE (-3265 4185);
FORCEPROP 1 LASTPIN (-3275 4175) BN 7
J 0
(-3287 4183);
DISPLAY 0.489362 (-3287 4183);
PAINT GREEN (-3287 4183);
FORCEPROP 2 LAST CDS_LIB mstr_standard
J 0
(-3225 4175);
DISPLAY 0.723404 (-3225 4175);
PAINT MONO (-3225 4175);
DISPLAY INVISIBLE (-3225 4175);
FORCEPROP 1 LAST BODY_TYPE PLUMBING
J 0
(-3225 4225);
DISPLAY 0.872340 (-3225 4225);
PAINT GREEN (-3225 4225);
DISPLAY INVISIBLE (-3225 4225);
FORCEPROP 1 LAST HDL_TAP TRUE
J 0
(-2900 4050);
DISPLAY 0.872340 (-2900 4050);
DISPLAY INVISIBLE (-2900 4050);
FORCEPROP 1 LAST PATH I206
J 0
(-3227 4175);
DISPLAY 0.872340 (-3227 4175);
PAINT GREEN (-3227 4175);
DISPLAY INVISIBLE (-3227 4175);
FORCEADD TAP..1
(-3225 4075);
FORCEPROP 3 LASTPIN (-3275 4075) SIG_NAME M_H_CPU1_SA_DQS_DN<6>
J 0
(-3265 4085);
DISPLAY 0.659574 (-3265 4085);
PAINT MONO (-3265 4085);
DISPLAY INVISIBLE (-3265 4085);
FORCEPROP 1 LASTPIN (-3275 4075) BN 6
J 0
(-3287 4083);
DISPLAY 0.489362 (-3287 4083);
PAINT GREEN (-3287 4083);
FORCEPROP 2 LAST CDS_LIB mstr_standard
J 0
(-3225 4075);
DISPLAY 0.723404 (-3225 4075);
PAINT MONO (-3225 4075);
DISPLAY INVISIBLE (-3225 4075);
FORCEPROP 1 LAST BODY_TYPE PLUMBING
J 0
(-3225 4125);
DISPLAY 0.872340 (-3225 4125);
PAINT GREEN (-3225 4125);
DISPLAY INVISIBLE (-3225 4125);
FORCEPROP 1 LAST HDL_TAP TRUE
J 0
(-2900 3950);
DISPLAY 0.872340 (-2900 3950);
DISPLAY INVISIBLE (-2900 3950);
FORCEPROP 1 LAST PATH I207
J 0
(-3227 4075);
DISPLAY 0.872340 (-3227 4075);
PAINT GREEN (-3227 4075);
DISPLAY INVISIBLE (-3227 4075);
FORCEADD TAP..1
(-3225 3975);
FORCEPROP 3 LASTPIN (-3275 3975) SIG_NAME M_H_CPU1_SA_DQS_DN<5>
J 0
(-3265 3985);
DISPLAY 0.659574 (-3265 3985);
PAINT MONO (-3265 3985);
DISPLAY INVISIBLE (-3265 3985);
FORCEPROP 1 LASTPIN (-3275 3975) BN 5
J 0
(-3287 3983);
DISPLAY 0.489362 (-3287 3983);
PAINT GREEN (-3287 3983);
FORCEPROP 2 LAST CDS_LIB mstr_standard
J 0
(-3225 3975);
DISPLAY 0.723404 (-3225 3975);
PAINT MONO (-3225 3975);
DISPLAY INVISIBLE (-3225 3975);
FORCEPROP 1 LAST BODY_TYPE PLUMBING
J 0
(-3225 4025);
DISPLAY 0.872340 (-3225 4025);
PAINT GREEN (-3225 4025);
DISPLAY INVISIBLE (-3225 4025);
FORCEPROP 1 LAST HDL_TAP TRUE
J 0
(-2900 3850);
DISPLAY 0.872340 (-2900 3850);
DISPLAY INVISIBLE (-2900 3850);
FORCEPROP 1 LAST PATH I208
J 0
(-3227 3975);
DISPLAY 0.872340 (-3227 3975);
PAINT GREEN (-3227 3975);
DISPLAY INVISIBLE (-3227 3975);
FORCEADD TAP..1
(-3225 3875);
FORCEPROP 3 LASTPIN (-3275 3875) SIG_NAME M_H_CPU1_SA_DQS_DN<4>
J 0
(-3265 3885);
DISPLAY 0.659574 (-3265 3885);
PAINT MONO (-3265 3885);
DISPLAY INVISIBLE (-3265 3885);
FORCEPROP 1 LASTPIN (-3275 3875) BN 4
J 0
(-3287 3883);
DISPLAY 0.489362 (-3287 3883);
PAINT GREEN (-3287 3883);
FORCEPROP 2 LAST CDS_LIB mstr_standard
J 0
(-3225 3875);
DISPLAY 0.723404 (-3225 3875);
PAINT MONO (-3225 3875);
DISPLAY INVISIBLE (-3225 3875);
FORCEPROP 1 LAST BODY_TYPE PLUMBING
J 0
(-3225 3925);
DISPLAY 0.872340 (-3225 3925);
PAINT GREEN (-3225 3925);
DISPLAY INVISIBLE (-3225 3925);
FORCEPROP 1 LAST HDL_TAP TRUE
J 0
(-2900 3750);
DISPLAY 0.872340 (-2900 3750);
DISPLAY INVISIBLE (-2900 3750);
FORCEPROP 1 LAST PATH I209
J 0
(-3227 3875);
DISPLAY 0.872340 (-3227 3875);
PAINT GREEN (-3227 3875);
DISPLAY INVISIBLE (-3227 3875);
FORCEADD OFFPAGE..1
(-8250 5450);
FORCEPROP 2 LAST $XR0 44 
J 0
(-8501 5450);
DISPLAY 0.638298 (-8501 5450);
PAINT MONO (-8501 5450);
FORCEPROP 2 LAST PATH I21
J 0
(-8450 5500);
DISPLAY 1.021277 (-8450 5500);
DISPLAY INVISIBLE (-8450 5500);
FORCEPROP 1 LAST COMMENT_BODY TRUE
J 0
(-8125 5350);
DISPLAY 0.872340 (-8125 5350);
PAINT GREEN (-8125 5350);
DISPLAY INVISIBLE (-8125 5350);
FORCEPROP 1 LAST OFFPAGE TRUE
J 0
(-7925 5325);
DISPLAY 0.872340 (-7925 5325);
PAINT GREEN (-7925 5325);
DISPLAY INVISIBLE (-7925 5325);
FORCEPROP 2 LAST CDS_LIB mstr_standard
J 0
(-8250 5450);
DISPLAY 0.723404 (-8250 5450);
PAINT MONO (-8250 5450);
DISPLAY INVISIBLE (-8250 5450);
FORCEADD TAP..1
(-3225 3575);
FORCEPROP 3 LASTPIN (-3275 3575) SIG_NAME M_H_CPU1_SA_DQS_DN<1>
J 0
(-3265 3585);
DISPLAY 0.659574 (-3265 3585);
PAINT MONO (-3265 3585);
DISPLAY INVISIBLE (-3265 3585);
FORCEPROP 1 LASTPIN (-3275 3575) BN 1
J 0
(-3287 3583);
DISPLAY 0.489362 (-3287 3583);
PAINT GREEN (-3287 3583);
FORCEPROP 2 LAST CDS_LIB mstr_standard
J 0
(-3225 3575);
DISPLAY 0.723404 (-3225 3575);
PAINT MONO (-3225 3575);
DISPLAY INVISIBLE (-3225 3575);
FORCEPROP 1 LAST BODY_TYPE PLUMBING
J 0
(-3225 3625);
DISPLAY 0.872340 (-3225 3625);
PAINT GREEN (-3225 3625);
DISPLAY INVISIBLE (-3225 3625);
FORCEPROP 1 LAST HDL_TAP TRUE
J 0
(-2900 3450);
DISPLAY 0.872340 (-2900 3450);
DISPLAY INVISIBLE (-2900 3450);
FORCEPROP 1 LAST PATH I210
J 0
(-3227 3575);
DISPLAY 0.872340 (-3227 3575);
PAINT GREEN (-3227 3575);
DISPLAY INVISIBLE (-3227 3575);
FORCEADD TAP..1
(-3225 3475);
FORCEPROP 3 LASTPIN (-3275 3475) SIG_NAME M_H_CPU1_SA_DQS_DN<0>
J 0
(-3265 3485);
DISPLAY 0.659574 (-3265 3485);
PAINT MONO (-3265 3485);
DISPLAY INVISIBLE (-3265 3485);
FORCEPROP 1 LASTPIN (-3275 3475) BN 0
J 0
(-3287 3483);
DISPLAY 0.489362 (-3287 3483);
PAINT GREEN (-3287 3483);
FORCEPROP 2 LAST CDS_LIB mstr_standard
J 0
(-3225 3475);
DISPLAY 0.723404 (-3225 3475);
PAINT MONO (-3225 3475);
DISPLAY INVISIBLE (-3225 3475);
FORCEPROP 1 LAST BODY_TYPE PLUMBING
J 0
(-3225 3525);
DISPLAY 0.872340 (-3225 3525);
PAINT GREEN (-3225 3525);
DISPLAY INVISIBLE (-3225 3525);
FORCEPROP 1 LAST HDL_TAP TRUE
J 0
(-2900 3350);
DISPLAY 0.872340 (-2900 3350);
DISPLAY INVISIBLE (-2900 3350);
FORCEPROP 1 LAST PATH I211
J 0
(-3227 3475);
DISPLAY 0.872340 (-3227 3475);
PAINT GREEN (-3227 3475);
DISPLAY INVISIBLE (-3227 3475);
FORCEADD TAP..1
(-3225 3225);
FORCEPROP 3 LASTPIN (-3275 3225) SIG_NAME M_H_CPU1_SB_DQS_DN<8>
J 0
(-3265 3235);
DISPLAY 0.659574 (-3265 3235);
PAINT MONO (-3265 3235);
DISPLAY INVISIBLE (-3265 3235);
FORCEPROP 1 LASTPIN (-3275 3225) BN 8
J 0
(-3287 3233);
DISPLAY 0.489362 (-3287 3233);
PAINT GREEN (-3287 3233);
FORCEPROP 2 LAST CDS_LIB mstr_standard
J 0
(-3225 3225);
DISPLAY 0.723404 (-3225 3225);
PAINT MONO (-3225 3225);
DISPLAY INVISIBLE (-3225 3225);
FORCEPROP 1 LAST BODY_TYPE PLUMBING
J 0
(-3225 3275);
DISPLAY 0.872340 (-3225 3275);
PAINT GREEN (-3225 3275);
DISPLAY INVISIBLE (-3225 3275);
FORCEPROP 1 LAST HDL_TAP TRUE
J 0
(-2900 3100);
DISPLAY 0.872340 (-2900 3100);
DISPLAY INVISIBLE (-2900 3100);
FORCEPROP 1 LAST PATH I212
J 0
(-3227 3225);
DISPLAY 0.872340 (-3227 3225);
PAINT GREEN (-3227 3225);
DISPLAY INVISIBLE (-3227 3225);
FORCEADD TAP..1
(-3225 3325);
FORCEPROP 3 LASTPIN (-3275 3325) SIG_NAME M_H_CPU1_SB_DQS_DN<9>
J 0
(-3265 3335);
DISPLAY 0.659574 (-3265 3335);
PAINT MONO (-3265 3335);
DISPLAY INVISIBLE (-3265 3335);
FORCEPROP 1 LASTPIN (-3275 3325) BN 9
J 0
(-3287 3333);
DISPLAY 0.489362 (-3287 3333);
PAINT GREEN (-3287 3333);
FORCEPROP 2 LAST CDS_LIB mstr_standard
J 0
(-3225 3325);
DISPLAY 0.723404 (-3225 3325);
PAINT MONO (-3225 3325);
DISPLAY INVISIBLE (-3225 3325);
FORCEPROP 1 LAST BODY_TYPE PLUMBING
J 0
(-3225 3375);
DISPLAY 0.872340 (-3225 3375);
PAINT GREEN (-3225 3375);
DISPLAY INVISIBLE (-3225 3375);
FORCEPROP 1 LAST HDL_TAP TRUE
J 0
(-2900 3200);
DISPLAY 0.872340 (-2900 3200);
DISPLAY INVISIBLE (-2900 3200);
FORCEPROP 1 LAST PATH I213
J 0
(-3227 3325);
DISPLAY 0.872340 (-3227 3325);
PAINT GREEN (-3227 3325);
DISPLAY INVISIBLE (-3227 3325);
FORCEADD TAP..1
(-3425 4225);
FORCEPROP 3 LASTPIN (-3475 4225) SIG_NAME M_H_CPU1_SA_DQS_DP<7>
J 0
(-3465 4235);
DISPLAY 0.659574 (-3465 4235);
PAINT MONO (-3465 4235);
DISPLAY INVISIBLE (-3465 4235);
FORCEPROP 1 LASTPIN (-3475 4225) BN 7
J 0
(-3487 4233);
DISPLAY 0.489362 (-3487 4233);
PAINT GREEN (-3487 4233);
FORCEPROP 2 LAST CDS_LIB mstr_standard
J 0
(-3425 4225);
DISPLAY 0.723404 (-3425 4225);
PAINT MONO (-3425 4225);
DISPLAY INVISIBLE (-3425 4225);
FORCEPROP 1 LAST BODY_TYPE PLUMBING
J 0
(-3425 4275);
DISPLAY 0.872340 (-3425 4275);
PAINT GREEN (-3425 4275);
DISPLAY INVISIBLE (-3425 4275);
FORCEPROP 1 LAST HDL_TAP TRUE
J 0
(-3100 4100);
DISPLAY 0.872340 (-3100 4100);
DISPLAY INVISIBLE (-3100 4100);
FORCEPROP 1 LAST PATH I214
J 0
(-3427 4225);
DISPLAY 0.872340 (-3427 4225);
PAINT GREEN (-3427 4225);
DISPLAY INVISIBLE (-3427 4225);
FORCEADD TAP..1
(-3425 4125);
FORCEPROP 3 LASTPIN (-3475 4125) SIG_NAME M_H_CPU1_SA_DQS_DP<6>
J 0
(-3465 4135);
DISPLAY 0.659574 (-3465 4135);
PAINT MONO (-3465 4135);
DISPLAY INVISIBLE (-3465 4135);
FORCEPROP 1 LASTPIN (-3475 4125) BN 6
J 0
(-3487 4133);
DISPLAY 0.489362 (-3487 4133);
PAINT GREEN (-3487 4133);
FORCEPROP 2 LAST CDS_LIB mstr_standard
J 0
(-3425 4125);
DISPLAY 0.723404 (-3425 4125);
PAINT MONO (-3425 4125);
DISPLAY INVISIBLE (-3425 4125);
FORCEPROP 1 LAST BODY_TYPE PLUMBING
J 0
(-3425 4175);
DISPLAY 0.872340 (-3425 4175);
PAINT GREEN (-3425 4175);
DISPLAY INVISIBLE (-3425 4175);
FORCEPROP 1 LAST HDL_TAP TRUE
J 0
(-3100 4000);
DISPLAY 0.872340 (-3100 4000);
DISPLAY INVISIBLE (-3100 4000);
FORCEPROP 1 LAST PATH I215
J 0
(-3427 4125);
DISPLAY 0.872340 (-3427 4125);
PAINT GREEN (-3427 4125);
DISPLAY INVISIBLE (-3427 4125);
FORCEADD TAP..1
(-3425 3825);
FORCEPROP 3 LASTPIN (-3475 3825) SIG_NAME M_H_CPU1_SA_DQS_DP<3>
J 0
(-3465 3835);
DISPLAY 0.659574 (-3465 3835);
PAINT MONO (-3465 3835);
DISPLAY INVISIBLE (-3465 3835);
FORCEPROP 1 LASTPIN (-3475 3825) BN 3
J 0
(-3487 3833);
DISPLAY 0.489362 (-3487 3833);
PAINT GREEN (-3487 3833);
FORCEPROP 2 LAST CDS_LIB mstr_standard
J 0
(-3425 3825);
DISPLAY 0.723404 (-3425 3825);
PAINT MONO (-3425 3825);
DISPLAY INVISIBLE (-3425 3825);
FORCEPROP 1 LAST BODY_TYPE PLUMBING
J 0
(-3425 3875);
DISPLAY 0.872340 (-3425 3875);
PAINT GREEN (-3425 3875);
DISPLAY INVISIBLE (-3425 3875);
FORCEPROP 1 LAST HDL_TAP TRUE
J 0
(-3100 3700);
DISPLAY 0.872340 (-3100 3700);
DISPLAY INVISIBLE (-3100 3700);
FORCEPROP 1 LAST PATH I216
J 0
(-3427 3825);
DISPLAY 0.872340 (-3427 3825);
PAINT GREEN (-3427 3825);
DISPLAY INVISIBLE (-3427 3825);
FORCEADD TAP..1
(-3425 3725);
FORCEPROP 3 LASTPIN (-3475 3725) SIG_NAME M_H_CPU1_SA_DQS_DP<2>
J 0
(-3465 3735);
DISPLAY 0.659574 (-3465 3735);
PAINT MONO (-3465 3735);
DISPLAY INVISIBLE (-3465 3735);
FORCEPROP 1 LASTPIN (-3475 3725) BN 2
J 0
(-3487 3733);
DISPLAY 0.489362 (-3487 3733);
PAINT GREEN (-3487 3733);
FORCEPROP 2 LAST CDS_LIB mstr_standard
J 0
(-3425 3725);
DISPLAY 0.723404 (-3425 3725);
PAINT MONO (-3425 3725);
DISPLAY INVISIBLE (-3425 3725);
FORCEPROP 1 LAST BODY_TYPE PLUMBING
J 0
(-3425 3775);
DISPLAY 0.872340 (-3425 3775);
PAINT GREEN (-3425 3775);
DISPLAY INVISIBLE (-3425 3775);
FORCEPROP 1 LAST HDL_TAP TRUE
J 0
(-3100 3600);
DISPLAY 0.872340 (-3100 3600);
DISPLAY INVISIBLE (-3100 3600);
FORCEPROP 1 LAST PATH I217
J 0
(-3427 3725);
DISPLAY 0.872340 (-3427 3725);
PAINT GREEN (-3427 3725);
DISPLAY INVISIBLE (-3427 3725);
FORCEADD TAP..1
(-3425 3625);
FORCEPROP 3 LASTPIN (-3475 3625) SIG_NAME M_H_CPU1_SA_DQS_DP<1>
J 0
(-3465 3635);
DISPLAY 0.659574 (-3465 3635);
PAINT MONO (-3465 3635);
DISPLAY INVISIBLE (-3465 3635);
FORCEPROP 1 LASTPIN (-3475 3625) BN 1
J 0
(-3487 3633);
DISPLAY 0.489362 (-3487 3633);
PAINT GREEN (-3487 3633);
FORCEPROP 2 LAST CDS_LIB mstr_standard
J 0
(-3425 3625);
DISPLAY 0.723404 (-3425 3625);
PAINT MONO (-3425 3625);
DISPLAY INVISIBLE (-3425 3625);
FORCEPROP 1 LAST BODY_TYPE PLUMBING
J 0
(-3425 3675);
DISPLAY 0.872340 (-3425 3675);
PAINT GREEN (-3425 3675);
DISPLAY INVISIBLE (-3425 3675);
FORCEPROP 1 LAST HDL_TAP TRUE
J 0
(-3100 3500);
DISPLAY 0.872340 (-3100 3500);
DISPLAY INVISIBLE (-3100 3500);
FORCEPROP 1 LAST PATH I218
J 0
(-3427 3625);
DISPLAY 0.872340 (-3427 3625);
PAINT GREEN (-3427 3625);
DISPLAY INVISIBLE (-3427 3625);
FORCEADD TAP..1
(-3425 3525);
FORCEPROP 3 LASTPIN (-3475 3525) SIG_NAME M_H_CPU1_SA_DQS_DP<0>
J 0
(-3465 3535);
DISPLAY 0.659574 (-3465 3535);
PAINT MONO (-3465 3535);
DISPLAY INVISIBLE (-3465 3535);
FORCEPROP 1 LASTPIN (-3475 3525) BN 0
J 0
(-3487 3533);
DISPLAY 0.489362 (-3487 3533);
PAINT GREEN (-3487 3533);
FORCEPROP 2 LAST CDS_LIB mstr_standard
J 0
(-3425 3525);
DISPLAY 0.723404 (-3425 3525);
PAINT MONO (-3425 3525);
DISPLAY INVISIBLE (-3425 3525);
FORCEPROP 1 LAST BODY_TYPE PLUMBING
J 0
(-3425 3575);
DISPLAY 0.872340 (-3425 3575);
PAINT GREEN (-3425 3575);
DISPLAY INVISIBLE (-3425 3575);
FORCEPROP 1 LAST HDL_TAP TRUE
J 0
(-3100 3400);
DISPLAY 0.872340 (-3100 3400);
DISPLAY INVISIBLE (-3100 3400);
FORCEPROP 1 LAST PATH I219
J 0
(-3427 3525);
DISPLAY 0.872340 (-3427 3525);
PAINT GREEN (-3427 3525);
DISPLAY INVISIBLE (-3427 3525);
FORCEADD SCONN288_DDR506112002KQ..1
(-6800 3650);
FORCEPROP 1 LAST LOCATION J27
J 0
(-7250 5725);
DISPLAY 0.468085 (-7250 5725);
PAINT SKYBLUE (-7250 5725);
FORCEPROP 0 LAST $SEC 1
J 0
(-7250 5875);
DISPLAY 0.680851 (-7250 5875);
PAINT MONO (-7250 5875);
DISPLAY INVISIBLE (-7250 5875);
FORCEPROP 2 LAST CDS_SEC 1
J 0
(-7250 5875);
DISPLAY 1.021277 (-7250 5875);
DISPLAY INVISIBLE (-7250 5875);
FORCEPROP 0 LASTPIN (-7400 3050) $PN 62
J 2
(-7410 3060);
DISPLAY 0.680851 (-7410 3060);
PAINT MONO (-7410 3060);
FORCEPROP 0 LASTPIN (-7400 5100) $PN 66
J 2
(-7410 5110);
DISPLAY 0.680851 (-7410 5110);
PAINT MONO (-7410 5110);
FORCEPROP 0 LASTPIN (-7400 4700) $PN 76
J 2
(-7410 4710);
DISPLAY 0.680851 (-7410 4710);
PAINT MONO (-7410 4710);
FORCEPROP 0 LASTPIN (-7400 5150) $PN 211
J 2
(-7410 5160);
DISPLAY 0.680851 (-7410 5160);
PAINT MONO (-7410 5160);
FORCEPROP 0 LASTPIN (-7400 4750) $PN 221
J 2
(-7410 4760);
DISPLAY 0.680851 (-7410 4760);
PAINT MONO (-7410 4760);
FORCEPROP 0 LASTPIN (-7400 5200) $PN 68
J 2
(-7410 5210);
DISPLAY 0.680851 (-7410 5210);
PAINT MONO (-7410 5210);
FORCEPROP 0 LASTPIN (-7400 4800) $PN 78
J 2
(-7410 4810);
DISPLAY 0.680851 (-7410 4810);
PAINT MONO (-7410 4810);
FORCEPROP 0 LASTPIN (-7400 5250) $PN 213
J 2
(-7410 5260);
DISPLAY 0.680851 (-7410 5260);
PAINT MONO (-7410 5260);
FORCEPROP 0 LASTPIN (-7400 4850) $PN 223
J 2
(-7410 4860);
DISPLAY 0.680851 (-7410 4860);
PAINT MONO (-7410 4860);
FORCEPROP 0 LASTPIN (-7400 5300) $PN 70
J 2
(-7410 5310);
DISPLAY 0.680851 (-7410 5310);
PAINT MONO (-7410 5310);
FORCEPROP 0 LASTPIN (-7400 4900) $PN 80
J 2
(-7410 4910);
DISPLAY 0.680851 (-7410 4910);
PAINT MONO (-7410 4910);
FORCEPROP 0 LASTPIN (-7400 5350) $PN 215
J 2
(-7410 5360);
DISPLAY 0.680851 (-7410 5360);
PAINT MONO (-7410 5360);
FORCEPROP 0 LASTPIN (-7400 4950) $PN 225
J 2
(-7410 4960);
DISPLAY 0.680851 (-7410 4960);
PAINT MONO (-7410 4960);
FORCEPROP 0 LASTPIN (-7400 5400) $PN 72
J 2
(-7410 5410);
DISPLAY 0.680851 (-7410 5410);
PAINT MONO (-7410 5410);
FORCEPROP 0 LASTPIN (-7400 5000) $PN 82
J 2
(-7410 5010);
DISPLAY 0.680851 (-7410 5010);
PAINT MONO (-7410 5010);
FORCEPROP 0 LASTPIN (-7400 3650) $PN 51
J 2
(-7410 3660);
DISPLAY 0.680851 (-7410 3660);
PAINT MONO (-7410 3660);
FORCEPROP 0 LASTPIN (-7400 3200) $PN 96
J 2
(-7410 3210);
DISPLAY 0.680851 (-7410 3210);
PAINT MONO (-7410 3210);
FORCEPROP 0 LASTPIN (-7400 3700) $PN 53
J 2
(-7410 3710);
DISPLAY 0.680851 (-7410 3710);
PAINT MONO (-7410 3710);
FORCEPROP 0 LASTPIN (-7400 3250) $PN 98
J 2
(-7410 3260);
DISPLAY 0.680851 (-7410 3260);
PAINT MONO (-7410 3260);
FORCEPROP 0 LASTPIN (-7400 3750) $PN 196
J 2
(-7410 3760);
DISPLAY 0.680851 (-7410 3760);
PAINT MONO (-7410 3760);
FORCEPROP 0 LASTPIN (-7400 3300) $PN 241
J 2
(-7410 3310);
DISPLAY 0.680851 (-7410 3310);
PAINT MONO (-7410 3310);
FORCEPROP 0 LASTPIN (-7400 3800) $PN 198
J 2
(-7410 3810);
DISPLAY 0.680851 (-7410 3810);
PAINT MONO (-7410 3810);
FORCEPROP 0 LASTPIN (-7400 3350) $PN 243
J 2
(-7410 3360);
DISPLAY 0.680851 (-7410 3360);
PAINT MONO (-7410 3360);
FORCEPROP 0 LASTPIN (-7400 3850) $PN 58
J 2
(-7410 3860);
DISPLAY 0.680851 (-7410 3860);
PAINT MONO (-7410 3860);
FORCEPROP 0 LASTPIN (-7400 3400) $PN 89
J 2
(-7410 3410);
DISPLAY 0.680851 (-7410 3410);
PAINT MONO (-7410 3410);
FORCEPROP 0 LASTPIN (-7400 3900) $PN 60
J 2
(-7410 3910);
DISPLAY 0.680851 (-7410 3910);
PAINT MONO (-7410 3910);
FORCEPROP 0 LASTPIN (-7400 3450) $PN 91
J 2
(-7410 3460);
DISPLAY 0.680851 (-7410 3460);
PAINT MONO (-7410 3460);
FORCEPROP 0 LASTPIN (-7400 3950) $PN 203
J 2
(-7410 3960);
DISPLAY 0.680851 (-7410 3960);
PAINT MONO (-7410 3960);
FORCEPROP 0 LASTPIN (-7400 3500) $PN 234
J 2
(-7410 3510);
DISPLAY 0.680851 (-7410 3510);
PAINT MONO (-7410 3510);
FORCEPROP 0 LASTPIN (-7400 4000) $PN 205
J 2
(-7410 4010);
DISPLAY 0.680851 (-7410 4010);
PAINT MONO (-7410 4010);
FORCEPROP 0 LASTPIN (-7400 3550) $PN 236
J 2
(-7410 3560);
DISPLAY 0.680851 (-7410 3560);
PAINT MONO (-7410 3560);
FORCEPROP 0 LASTPIN (-7400 4100) $PN 218
J 2
(-7410 4110);
DISPLAY 0.680851 (-7410 4110);
PAINT MONO (-7410 4110);
FORCEPROP 0 LASTPIN (-7400 4150) $PN 217
J 2
(-7410 4160);
DISPLAY 0.680851 (-7410 4160);
PAINT MONO (-7410 4160);
FORCEPROP 0 LASTPIN (-7400 4400) $PN 64
J 2
(-7410 4410);
DISPLAY 0.680851 (-7410 4410);
PAINT MONO (-7410 4410);
FORCEPROP 0 LASTPIN (-7400 4250) $PN 84
J 2
(-7410 4260);
DISPLAY 0.680851 (-7410 4260);
PAINT MONO (-7410 4260);
FORCEPROP 0 LASTPIN (-7400 4450) $PN 209
J 2
(-7410 4460);
DISPLAY 0.680851 (-7410 4460);
PAINT MONO (-7410 4460);
FORCEPROP 0 LASTPIN (-7400 4300) $PN 229
J 2
(-7410 4310);
DISPLAY 0.680851 (-7410 4310);
PAINT MONO (-7410 4310);
FORCEPROP 0 LASTPIN (-6200 3850) $PN 7
J 0
(-6190 3860);
DISPLAY 0.680851 (-6190 3860);
PAINT MONO (-6190 3860);
FORCEPROP 0 LASTPIN (-6200 2200) $PN 100
J 0
(-6190 2210);
DISPLAY 0.680851 (-6190 2210);
PAINT MONO (-6190 2210);
FORCEPROP 0 LASTPIN (-6200 3900) $PN 9
J 0
(-6190 3910);
DISPLAY 0.680851 (-6190 3910);
PAINT MONO (-6190 3910);
FORCEPROP 0 LASTPIN (-6200 2250) $PN 102
J 0
(-6190 2260);
DISPLAY 0.680851 (-6190 2260);
PAINT MONO (-6190 2260);
FORCEPROP 0 LASTPIN (-6200 3950) $PN 152
J 0
(-6190 3960);
DISPLAY 0.680851 (-6190 3960);
PAINT MONO (-6190 3960);
FORCEPROP 0 LASTPIN (-6200 2300) $PN 245
J 0
(-6190 2310);
DISPLAY 0.680851 (-6190 2310);
PAINT MONO (-6190 2310);
FORCEPROP 0 LASTPIN (-6200 4000) $PN 154
J 0
(-6190 4010);
DISPLAY 0.680851 (-6190 4010);
PAINT MONO (-6190 4010);
FORCEPROP 0 LASTPIN (-6200 2350) $PN 247
J 0
(-6190 2360);
DISPLAY 0.680851 (-6190 2360);
PAINT MONO (-6190 2360);
FORCEPROP 0 LASTPIN (-6200 4050) $PN 14
J 0
(-6190 4060);
DISPLAY 0.680851 (-6190 4060);
PAINT MONO (-6190 4060);
FORCEPROP 0 LASTPIN (-6200 2400) $PN 107
J 0
(-6190 2410);
DISPLAY 0.680851 (-6190 2410);
PAINT MONO (-6190 2410);
FORCEPROP 0 LASTPIN (-6200 4100) $PN 16
J 0
(-6190 4110);
DISPLAY 0.680851 (-6190 4110);
PAINT MONO (-6190 4110);
FORCEPROP 0 LASTPIN (-6200 2450) $PN 109
J 0
(-6190 2460);
DISPLAY 0.680851 (-6190 2460);
PAINT MONO (-6190 2460);
FORCEPROP 0 LASTPIN (-6200 4150) $PN 159
J 0
(-6190 4160);
DISPLAY 0.680851 (-6190 4160);
PAINT MONO (-6190 4160);
FORCEPROP 0 LASTPIN (-6200 2500) $PN 252
J 0
(-6190 2510);
DISPLAY 0.680851 (-6190 2510);
PAINT MONO (-6190 2510);
FORCEPROP 0 LASTPIN (-6200 4200) $PN 161
J 0
(-6190 4210);
DISPLAY 0.680851 (-6190 4210);
PAINT MONO (-6190 4210);
FORCEPROP 0 LASTPIN (-6200 2550) $PN 254
J 0
(-6190 2560);
DISPLAY 0.680851 (-6190 2560);
PAINT MONO (-6190 2560);
FORCEPROP 0 LASTPIN (-6200 4250) $PN 18
J 0
(-6190 4260);
DISPLAY 0.680851 (-6190 4260);
PAINT MONO (-6190 4260);
FORCEPROP 0 LASTPIN (-6200 2600) $PN 111
J 0
(-6190 2610);
DISPLAY 0.680851 (-6190 2610);
PAINT MONO (-6190 2610);
FORCEPROP 0 LASTPIN (-6200 4300) $PN 20
J 0
(-6190 4310);
DISPLAY 0.680851 (-6190 4310);
PAINT MONO (-6190 4310);
FORCEPROP 0 LASTPIN (-6200 2650) $PN 113
J 0
(-6190 2660);
DISPLAY 0.680851 (-6190 2660);
PAINT MONO (-6190 2660);
FORCEPROP 0 LASTPIN (-6200 4350) $PN 163
J 0
(-6190 4360);
DISPLAY 0.680851 (-6190 4360);
PAINT MONO (-6190 4360);
FORCEPROP 0 LASTPIN (-6200 2700) $PN 256
J 0
(-6190 2710);
DISPLAY 0.680851 (-6190 2710);
PAINT MONO (-6190 2710);
FORCEPROP 0 LASTPIN (-6200 4400) $PN 165
J 0
(-6190 4410);
DISPLAY 0.680851 (-6190 4410);
PAINT MONO (-6190 4410);
FORCEPROP 0 LASTPIN (-6200 2750) $PN 258
J 0
(-6190 2760);
DISPLAY 0.680851 (-6190 2760);
PAINT MONO (-6190 2760);
FORCEPROP 0 LASTPIN (-6200 4450) $PN 25
J 0
(-6190 4460);
DISPLAY 0.680851 (-6190 4460);
PAINT MONO (-6190 4460);
FORCEPROP 0 LASTPIN (-6200 2800) $PN 118
J 0
(-6190 2810);
DISPLAY 0.680851 (-6190 2810);
PAINT MONO (-6190 2810);
FORCEPROP 0 LASTPIN (-6200 4500) $PN 27
J 0
(-6190 4510);
DISPLAY 0.680851 (-6190 4510);
PAINT MONO (-6190 4510);
FORCEPROP 0 LASTPIN (-6200 2850) $PN 120
J 0
(-6190 2860);
DISPLAY 0.680851 (-6190 2860);
PAINT MONO (-6190 2860);
FORCEPROP 0 LASTPIN (-6200 4550) $PN 170
J 0
(-6190 4560);
DISPLAY 0.680851 (-6190 4560);
PAINT MONO (-6190 4560);
FORCEPROP 0 LASTPIN (-6200 2900) $PN 263
J 0
(-6190 2910);
DISPLAY 0.680851 (-6190 2910);
PAINT MONO (-6190 2910);
FORCEPROP 0 LASTPIN (-6200 4600) $PN 172
J 0
(-6190 4610);
DISPLAY 0.680851 (-6190 4610);
PAINT MONO (-6190 4610);
FORCEPROP 0 LASTPIN (-6200 2950) $PN 265
J 0
(-6190 2960);
DISPLAY 0.680851 (-6190 2960);
PAINT MONO (-6190 2960);
FORCEPROP 0 LASTPIN (-6200 4650) $PN 29
J 0
(-6190 4660);
DISPLAY 0.680851 (-6190 4660);
PAINT MONO (-6190 4660);
FORCEPROP 0 LASTPIN (-6200 3000) $PN 122
J 0
(-6190 3010);
DISPLAY 0.680851 (-6190 3010);
PAINT MONO (-6190 3010);
FORCEPROP 0 LASTPIN (-6200 4700) $PN 31
J 0
(-6190 4710);
DISPLAY 0.680851 (-6190 4710);
PAINT MONO (-6190 4710);
FORCEPROP 0 LASTPIN (-6200 3050) $PN 124
J 0
(-6190 3060);
DISPLAY 0.680851 (-6190 3060);
PAINT MONO (-6190 3060);
FORCEPROP 0 LASTPIN (-6200 4750) $PN 174
J 0
(-6190 4760);
DISPLAY 0.680851 (-6190 4760);
PAINT MONO (-6190 4760);
FORCEPROP 0 LASTPIN (-6200 3100) $PN 267
J 0
(-6190 3110);
DISPLAY 0.680851 (-6190 3110);
PAINT MONO (-6190 3110);
FORCEPROP 0 LASTPIN (-6200 4800) $PN 176
J 0
(-6190 4810);
DISPLAY 0.680851 (-6190 4810);
PAINT MONO (-6190 4810);
FORCEPROP 0 LASTPIN (-6200 3150) $PN 269
J 0
(-6190 3160);
DISPLAY 0.680851 (-6190 3160);
PAINT MONO (-6190 3160);
FORCEPROP 0 LASTPIN (-6200 4850) $PN 36
J 0
(-6190 4860);
DISPLAY 0.680851 (-6190 4860);
PAINT MONO (-6190 4860);
FORCEPROP 0 LASTPIN (-6200 3200) $PN 129
J 0
(-6190 3210);
DISPLAY 0.680851 (-6190 3210);
PAINT MONO (-6190 3210);
FORCEPROP 0 LASTPIN (-6200 4900) $PN 38
J 0
(-6190 4910);
DISPLAY 0.680851 (-6190 4910);
PAINT MONO (-6190 4910);
FORCEPROP 0 LASTPIN (-6200 3250) $PN 131
J 0
(-6190 3260);
DISPLAY 0.680851 (-6190 3260);
PAINT MONO (-6190 3260);
FORCEPROP 0 LASTPIN (-6200 4950) $PN 181
J 0
(-6190 4960);
DISPLAY 0.680851 (-6190 4960);
PAINT MONO (-6190 4960);
FORCEPROP 0 LASTPIN (-6200 3300) $PN 274
J 0
(-6190 3310);
DISPLAY 0.680851 (-6190 3310);
PAINT MONO (-6190 3310);
FORCEPROP 0 LASTPIN (-6200 5000) $PN 183
J 0
(-6190 5010);
DISPLAY 0.680851 (-6190 5010);
PAINT MONO (-6190 5010);
FORCEPROP 0 LASTPIN (-6200 3350) $PN 276
J 0
(-6190 3360);
DISPLAY 0.680851 (-6190 3360);
PAINT MONO (-6190 3360);
FORCEPROP 0 LASTPIN (-6200 5050) $PN 40
J 0
(-6190 5060);
DISPLAY 0.680851 (-6190 5060);
PAINT MONO (-6190 5060);
FORCEPROP 0 LASTPIN (-6200 3400) $PN 133
J 0
(-6190 3410);
DISPLAY 0.680851 (-6190 3410);
PAINT MONO (-6190 3410);
FORCEPROP 0 LASTPIN (-6200 5100) $PN 42
J 0
(-6190 5110);
DISPLAY 0.680851 (-6190 5110);
PAINT MONO (-6190 5110);
FORCEPROP 0 LASTPIN (-6200 3450) $PN 135
J 0
(-6190 3460);
DISPLAY 0.680851 (-6190 3460);
PAINT MONO (-6190 3460);
FORCEPROP 0 LASTPIN (-6200 5150) $PN 185
J 0
(-6190 5160);
DISPLAY 0.680851 (-6190 5160);
PAINT MONO (-6190 5160);
FORCEPROP 0 LASTPIN (-6200 3500) $PN 278
J 0
(-6190 3510);
DISPLAY 0.680851 (-6190 3510);
PAINT MONO (-6190 3510);
FORCEPROP 0 LASTPIN (-6200 5200) $PN 187
J 0
(-6190 5210);
DISPLAY 0.680851 (-6190 5210);
PAINT MONO (-6190 5210);
FORCEPROP 0 LASTPIN (-6200 3550) $PN 280
J 0
(-6190 3560);
DISPLAY 0.680851 (-6190 3560);
PAINT MONO (-6190 3560);
FORCEPROP 0 LASTPIN (-6200 5250) $PN 47
J 0
(-6190 5260);
DISPLAY 0.680851 (-6190 5260);
PAINT MONO (-6190 5260);
FORCEPROP 0 LASTPIN (-6200 3600) $PN 140
J 0
(-6190 3610);
DISPLAY 0.680851 (-6190 3610);
PAINT MONO (-6190 3610);
FORCEPROP 0 LASTPIN (-6200 5300) $PN 49
J 0
(-6190 5310);
DISPLAY 0.680851 (-6190 5310);
PAINT MONO (-6190 5310);
FORCEPROP 0 LASTPIN (-6200 3650) $PN 142
J 0
(-6190 3660);
DISPLAY 0.680851 (-6190 3660);
PAINT MONO (-6190 3660);
FORCEPROP 0 LASTPIN (-6200 5350) $PN 192
J 0
(-6190 5360);
DISPLAY 0.680851 (-6190 5360);
PAINT MONO (-6190 5360);
FORCEPROP 0 LASTPIN (-6200 3700) $PN 285
J 0
(-6190 3710);
DISPLAY 0.680851 (-6190 3710);
PAINT MONO (-6190 3710);
FORCEPROP 0 LASTPIN (-6200 5400) $PN 194
J 0
(-6190 5410);
DISPLAY 0.680851 (-6190 5410);
PAINT MONO (-6190 5410);
FORCEPROP 0 LASTPIN (-6200 3750) $PN 287
J 0
(-6190 3760);
DISPLAY 0.680851 (-6190 3760);
PAINT MONO (-6190 3760);
FORCEPROP 0 LASTPIN (-7400 2900) $PN 148
J 2
(-7410 2910);
DISPLAY 0.680851 (-7410 2910);
PAINT MONO (-7410 2910);
FORCEPROP 0 LASTPIN (-7400 2800) $PN 4
J 2
(-7410 2810);
DISPLAY 0.680851 (-7410 2810);
PAINT MONO (-7410 2810);
FORCEPROP 0 LASTPIN (-7400 2850) $PN 5
J 2
(-7410 2860);
DISPLAY 0.680851 (-7410 2860);
PAINT MONO (-7410 2860);
FORCEPROP 0 LASTPIN (-7400 2000) $PN 86
J 2
(-7410 2010);
DISPLAY 0.680851 (-7410 2010);
PAINT MONO (-7410 2010);
FORCEPROP 0 LASTPIN (-7400 1950) $PN 87
J 2
(-7410 1960);
DISPLAY 0.680851 (-7410 1960);
PAINT MONO (-7410 1960);
FORCEPROP 0 LASTPIN (-7400 4600) $PN 74
J 2
(-7410 4610);
DISPLAY 0.680851 (-7410 4610);
PAINT MONO (-7410 4610);
FORCEPROP 0 LASTPIN (-7400 4550) $PN 227
J 2
(-7410 4560);
DISPLAY 0.680851 (-7410 4560);
PAINT MONO (-7410 4560);
FORCEPROP 0 LASTPIN (-7400 2550) $PN 147
J 2
(-7410 2560);
DISPLAY 0.680851 (-7410 2560);
PAINT MONO (-7410 2560);
FORCEPROP 0 LASTPIN (-7400 3100) $PN 207
J 2
(-7410 3110);
DISPLAY 0.680851 (-7410 3110);
PAINT MONO (-7410 3110);
FORCEPROP 0 LASTPIN (-7400 2150) $PN 2
J 2
(-7410 2160);
DISPLAY 0.680851 (-7410 2160);
PAINT MONO (-7410 2160);
FORCEPROP 0 LASTPIN (-7400 2200) $PN 144
J 2
(-7410 2210);
DISPLAY 0.680851 (-7410 2210);
PAINT MONO (-7410 2210);
FORCEPROP 0 LASTPIN (-7400 2250) $PN 149
J 2
(-7410 2260);
DISPLAY 0.680851 (-7410 2260);
PAINT MONO (-7410 2260);
FORCEPROP 0 LASTPIN (-7400 2300) $PN 150
J 2
(-7410 2310);
DISPLAY 0.680851 (-7410 2310);
PAINT MONO (-7410 2310);
FORCEPROP 0 LASTPIN (-7400 2350) $PN 220
J 2
(-7410 2360);
DISPLAY 0.680851 (-7410 2360);
PAINT MONO (-7410 2360);
FORCEPROP 0 LASTPIN (-7400 2400) $PN 231
J 2
(-7410 2410);
DISPLAY 0.680851 (-7410 2410);
PAINT MONO (-7410 2410);
FORCEPROP 0 LASTPIN (-7400 2450) $PN 232
J 2
(-7410 2460);
DISPLAY 0.680851 (-7410 2460);
PAINT MONO (-7410 2460);
FORCEPROP 0 LASTPIN (-7400 2950) $PN 3
J 2
(-7410 2960);
DISPLAY 0.680851 (-7410 2960);
PAINT MONO (-7410 2960);
FORCEPROP 2 LAST VALUE SCONN288_DDR506112002KQ
J 0
(-7250 5775);
DISPLAY 0.489362 (-7250 5775);
PAINT SKYBLUE (-7250 5775);
FORCEPROP 2 LAST PART_TYPE SMLF
J 0
(-7250 5825);
DISPLAY 1.021277 (-7250 5825);
FORCEPROP 1 LAST PART_NUMBER DFHST8FS479
J 0
(-7250 5650);
DISPLAY 0.468085 (-7250 5650);
PAINT SKYBLUE (-7250 5650);
FORCEPROP 1 LAST MATERIAL IO
J 0
(-7250 5575);
DISPLAY 0.468085 (-7250 5575);
PAINT SKYBLUE (-7250 5575);
FORCEPROP 1 LAST CDS_LMAN_SYM_OUTLINE -450,1900,450,-1850
J 0
(-6800 3650);
DISPLAY 0.468085 (-6800 3650);
PAINT GREEN (-6800 3650);
DISPLAY INVISIBLE (-6800 3650);
FORCEPROP 1 LAST PATH I22
J 0
(-6800 3650);
DISPLAY 0.723404 (-6800 3650);
PAINT GREEN (-6800 3650);
DISPLAY INVISIBLE (-6800 3650);
FORCEPROP 1 LAST NEEDS_NO_SIZE TRUE
J 0
(-6800 3650);
DISPLAY 0.723404 (-6800 3650);
PAINT GREEN (-6800 3650);
DISPLAY INVISIBLE (-6800 3650);
FORCEPROP 2 LAST CDS_LIB pure_quanta
J 0
(-6800 3650);
DISPLAY INVISIBLE (-6800 3650);
FORCEADD TAP..1
(-3425 3375);
FORCEPROP 3 LASTPIN (-3475 3375) SIG_NAME M_H_CPU1_SB_DQS_DP<9>
J 0
(-3465 3385);
DISPLAY 0.659574 (-3465 3385);
PAINT MONO (-3465 3385);
DISPLAY INVISIBLE (-3465 3385);
FORCEPROP 1 LASTPIN (-3475 3375) BN 9
J 0
(-3487 3383);
DISPLAY 0.489362 (-3487 3383);
PAINT GREEN (-3487 3383);
FORCEPROP 2 LAST CDS_LIB mstr_standard
J 0
(-3425 3375);
DISPLAY 0.723404 (-3425 3375);
PAINT MONO (-3425 3375);
DISPLAY INVISIBLE (-3425 3375);
FORCEPROP 1 LAST BODY_TYPE PLUMBING
J 0
(-3425 3425);
DISPLAY 0.872340 (-3425 3425);
PAINT GREEN (-3425 3425);
DISPLAY INVISIBLE (-3425 3425);
FORCEPROP 1 LAST HDL_TAP TRUE
J 0
(-3100 3250);
DISPLAY 0.872340 (-3100 3250);
DISPLAY INVISIBLE (-3100 3250);
FORCEPROP 1 LAST PATH I220
J 0
(-3427 3375);
DISPLAY 0.872340 (-3427 3375);
PAINT GREEN (-3427 3375);
DISPLAY INVISIBLE (-3427 3375);
FORCEADD TAP..1
(-3425 3275);
FORCEPROP 3 LASTPIN (-3475 3275) SIG_NAME M_H_CPU1_SB_DQS_DP<8>
J 0
(-3465 3285);
DISPLAY 0.659574 (-3465 3285);
PAINT MONO (-3465 3285);
DISPLAY INVISIBLE (-3465 3285);
FORCEPROP 1 LASTPIN (-3475 3275) BN 8
J 0
(-3487 3283);
DISPLAY 0.489362 (-3487 3283);
PAINT GREEN (-3487 3283);
FORCEPROP 2 LAST CDS_LIB mstr_standard
J 0
(-3425 3275);
DISPLAY 0.723404 (-3425 3275);
PAINT MONO (-3425 3275);
DISPLAY INVISIBLE (-3425 3275);
FORCEPROP 1 LAST BODY_TYPE PLUMBING
J 0
(-3425 3325);
DISPLAY 0.872340 (-3425 3325);
PAINT GREEN (-3425 3325);
DISPLAY INVISIBLE (-3425 3325);
FORCEPROP 1 LAST HDL_TAP TRUE
J 0
(-3100 3150);
DISPLAY 0.872340 (-3100 3150);
DISPLAY INVISIBLE (-3100 3150);
FORCEPROP 1 LAST PATH I221
J 0
(-3427 3275);
DISPLAY 0.872340 (-3427 3275);
PAINT GREEN (-3427 3275);
DISPLAY INVISIBLE (-3427 3275);
FORCEADD TAP..1
(-3225 3125);
FORCEPROP 3 LASTPIN (-3275 3125) SIG_NAME M_H_CPU1_SB_DQS_DN<7>
J 0
(-3265 3135);
DISPLAY 0.659574 (-3265 3135);
PAINT MONO (-3265 3135);
DISPLAY INVISIBLE (-3265 3135);
FORCEPROP 1 LASTPIN (-3275 3125) BN 7
J 0
(-3287 3133);
DISPLAY 0.489362 (-3287 3133);
PAINT GREEN (-3287 3133);
FORCEPROP 2 LAST CDS_LIB mstr_standard
J 0
(-3225 3125);
DISPLAY 0.723404 (-3225 3125);
PAINT MONO (-3225 3125);
DISPLAY INVISIBLE (-3225 3125);
FORCEPROP 1 LAST BODY_TYPE PLUMBING
J 0
(-3225 3175);
DISPLAY 0.872340 (-3225 3175);
PAINT GREEN (-3225 3175);
DISPLAY INVISIBLE (-3225 3175);
FORCEPROP 1 LAST HDL_TAP TRUE
J 0
(-2900 3000);
DISPLAY 0.872340 (-2900 3000);
DISPLAY INVISIBLE (-2900 3000);
FORCEPROP 1 LAST PATH I222
J 0
(-3227 3125);
DISPLAY 0.872340 (-3227 3125);
PAINT GREEN (-3227 3125);
DISPLAY INVISIBLE (-3227 3125);
FORCEADD TAP..1
(-3225 3025);
FORCEPROP 3 LASTPIN (-3275 3025) SIG_NAME M_H_CPU1_SB_DQS_DN<6>
J 0
(-3265 3035);
DISPLAY 0.659574 (-3265 3035);
PAINT MONO (-3265 3035);
DISPLAY INVISIBLE (-3265 3035);
FORCEPROP 1 LASTPIN (-3275 3025) BN 6
J 0
(-3287 3033);
DISPLAY 0.489362 (-3287 3033);
PAINT GREEN (-3287 3033);
FORCEPROP 2 LAST CDS_LIB mstr_standard
J 0
(-3225 3025);
DISPLAY 0.723404 (-3225 3025);
PAINT MONO (-3225 3025);
DISPLAY INVISIBLE (-3225 3025);
FORCEPROP 1 LAST BODY_TYPE PLUMBING
J 0
(-3225 3075);
DISPLAY 0.872340 (-3225 3075);
PAINT GREEN (-3225 3075);
DISPLAY INVISIBLE (-3225 3075);
FORCEPROP 1 LAST HDL_TAP TRUE
J 0
(-2900 2900);
DISPLAY 0.872340 (-2900 2900);
DISPLAY INVISIBLE (-2900 2900);
FORCEPROP 1 LAST PATH I223
J 0
(-3227 3025);
DISPLAY 0.872340 (-3227 3025);
PAINT GREEN (-3227 3025);
DISPLAY INVISIBLE (-3227 3025);
FORCEADD TAP..1
(-3225 2925);
FORCEPROP 3 LASTPIN (-3275 2925) SIG_NAME M_H_CPU1_SB_DQS_DN<5>
J 0
(-3265 2935);
DISPLAY 0.659574 (-3265 2935);
PAINT MONO (-3265 2935);
DISPLAY INVISIBLE (-3265 2935);
FORCEPROP 1 LASTPIN (-3275 2925) BN 5
J 0
(-3287 2933);
DISPLAY 0.489362 (-3287 2933);
PAINT GREEN (-3287 2933);
FORCEPROP 2 LAST CDS_LIB mstr_standard
J 0
(-3225 2925);
DISPLAY 0.723404 (-3225 2925);
PAINT MONO (-3225 2925);
DISPLAY INVISIBLE (-3225 2925);
FORCEPROP 1 LAST BODY_TYPE PLUMBING
J 0
(-3225 2975);
DISPLAY 0.872340 (-3225 2975);
PAINT GREEN (-3225 2975);
DISPLAY INVISIBLE (-3225 2975);
FORCEPROP 1 LAST HDL_TAP TRUE
J 0
(-2900 2800);
DISPLAY 0.872340 (-2900 2800);
DISPLAY INVISIBLE (-2900 2800);
FORCEPROP 1 LAST PATH I224
J 0
(-3227 2925);
DISPLAY 0.872340 (-3227 2925);
PAINT GREEN (-3227 2925);
DISPLAY INVISIBLE (-3227 2925);
FORCEADD TAP..1
(-3225 2725);
FORCEPROP 3 LASTPIN (-3275 2725) SIG_NAME M_H_CPU1_SB_DQS_DN<3>
J 0
(-3265 2735);
DISPLAY 0.659574 (-3265 2735);
PAINT MONO (-3265 2735);
DISPLAY INVISIBLE (-3265 2735);
FORCEPROP 1 LASTPIN (-3275 2725) BN 3
J 0
(-3287 2733);
DISPLAY 0.489362 (-3287 2733);
PAINT GREEN (-3287 2733);
FORCEPROP 2 LAST CDS_LIB mstr_standard
J 0
(-3225 2725);
DISPLAY 0.723404 (-3225 2725);
PAINT MONO (-3225 2725);
DISPLAY INVISIBLE (-3225 2725);
FORCEPROP 1 LAST BODY_TYPE PLUMBING
J 0
(-3225 2775);
DISPLAY 0.872340 (-3225 2775);
PAINT GREEN (-3225 2775);
DISPLAY INVISIBLE (-3225 2775);
FORCEPROP 1 LAST HDL_TAP TRUE
J 0
(-2900 2600);
DISPLAY 0.872340 (-2900 2600);
DISPLAY INVISIBLE (-2900 2600);
FORCEPROP 1 LAST PATH I225
J 0
(-3227 2725);
DISPLAY 0.872340 (-3227 2725);
PAINT GREEN (-3227 2725);
DISPLAY INVISIBLE (-3227 2725);
FORCEADD TAP..1
(-3225 2825);
FORCEPROP 3 LASTPIN (-3275 2825) SIG_NAME M_H_CPU1_SB_DQS_DN<4>
J 0
(-3265 2835);
DISPLAY 0.659574 (-3265 2835);
PAINT MONO (-3265 2835);
DISPLAY INVISIBLE (-3265 2835);
FORCEPROP 1 LASTPIN (-3275 2825) BN 4
J 0
(-3287 2833);
DISPLAY 0.489362 (-3287 2833);
PAINT GREEN (-3287 2833);
FORCEPROP 2 LAST CDS_LIB mstr_standard
J 0
(-3225 2825);
DISPLAY 0.723404 (-3225 2825);
PAINT MONO (-3225 2825);
DISPLAY INVISIBLE (-3225 2825);
FORCEPROP 1 LAST BODY_TYPE PLUMBING
J 0
(-3225 2875);
DISPLAY 0.872340 (-3225 2875);
PAINT GREEN (-3225 2875);
DISPLAY INVISIBLE (-3225 2875);
FORCEPROP 1 LAST HDL_TAP TRUE
J 0
(-2900 2700);
DISPLAY 0.872340 (-2900 2700);
DISPLAY INVISIBLE (-2900 2700);
FORCEPROP 1 LAST PATH I226
J 0
(-3227 2825);
DISPLAY 0.872340 (-3227 2825);
PAINT GREEN (-3227 2825);
DISPLAY INVISIBLE (-3227 2825);
FORCEADD TAP..1
(-3225 2625);
FORCEPROP 3 LASTPIN (-3275 2625) SIG_NAME M_H_CPU1_SB_DQS_DN<2>
J 0
(-3265 2635);
DISPLAY 0.659574 (-3265 2635);
PAINT MONO (-3265 2635);
DISPLAY INVISIBLE (-3265 2635);
FORCEPROP 1 LASTPIN (-3275 2625) BN 2
J 0
(-3287 2633);
DISPLAY 0.489362 (-3287 2633);
PAINT GREEN (-3287 2633);
FORCEPROP 2 LAST CDS_LIB mstr_standard
J 0
(-3225 2625);
DISPLAY 0.723404 (-3225 2625);
PAINT MONO (-3225 2625);
DISPLAY INVISIBLE (-3225 2625);
FORCEPROP 1 LAST BODY_TYPE PLUMBING
J 0
(-3225 2675);
DISPLAY 0.872340 (-3225 2675);
PAINT GREEN (-3225 2675);
DISPLAY INVISIBLE (-3225 2675);
FORCEPROP 1 LAST HDL_TAP TRUE
J 0
(-2900 2500);
DISPLAY 0.872340 (-2900 2500);
DISPLAY INVISIBLE (-2900 2500);
FORCEPROP 1 LAST PATH I227
J 0
(-3227 2625);
DISPLAY 0.872340 (-3227 2625);
PAINT GREEN (-3227 2625);
DISPLAY INVISIBLE (-3227 2625);
FORCEADD TAP..1
(-3225 2525);
FORCEPROP 3 LASTPIN (-3275 2525) SIG_NAME M_H_CPU1_SB_DQS_DN<1>
J 0
(-3265 2535);
DISPLAY 0.659574 (-3265 2535);
PAINT MONO (-3265 2535);
DISPLAY INVISIBLE (-3265 2535);
FORCEPROP 1 LASTPIN (-3275 2525) BN 1
J 0
(-3287 2533);
DISPLAY 0.489362 (-3287 2533);
PAINT GREEN (-3287 2533);
FORCEPROP 2 LAST CDS_LIB mstr_standard
J 0
(-3225 2525);
DISPLAY 0.723404 (-3225 2525);
PAINT MONO (-3225 2525);
DISPLAY INVISIBLE (-3225 2525);
FORCEPROP 1 LAST BODY_TYPE PLUMBING
J 0
(-3225 2575);
DISPLAY 0.872340 (-3225 2575);
PAINT GREEN (-3225 2575);
DISPLAY INVISIBLE (-3225 2575);
FORCEPROP 1 LAST HDL_TAP TRUE
J 0
(-2900 2400);
DISPLAY 0.872340 (-2900 2400);
DISPLAY INVISIBLE (-2900 2400);
FORCEPROP 1 LAST PATH I228
J 0
(-3227 2525);
DISPLAY 0.872340 (-3227 2525);
PAINT GREEN (-3227 2525);
DISPLAY INVISIBLE (-3227 2525);
FORCEADD TAP..1
(-3225 2425);
FORCEPROP 3 LASTPIN (-3275 2425) SIG_NAME M_H_CPU1_SB_DQS_DN<0>
J 0
(-3265 2435);
DISPLAY 0.659574 (-3265 2435);
PAINT MONO (-3265 2435);
DISPLAY INVISIBLE (-3265 2435);
FORCEPROP 1 LASTPIN (-3275 2425) BN 0
J 0
(-3287 2433);
DISPLAY 0.489362 (-3287 2433);
PAINT GREEN (-3287 2433);
FORCEPROP 2 LAST CDS_LIB mstr_standard
J 0
(-3225 2425);
DISPLAY 0.723404 (-3225 2425);
PAINT MONO (-3225 2425);
DISPLAY INVISIBLE (-3225 2425);
FORCEPROP 1 LAST BODY_TYPE PLUMBING
J 0
(-3225 2475);
DISPLAY 0.872340 (-3225 2475);
PAINT GREEN (-3225 2475);
DISPLAY INVISIBLE (-3225 2475);
FORCEPROP 1 LAST HDL_TAP TRUE
J 0
(-2900 2300);
DISPLAY 0.872340 (-2900 2300);
DISPLAY INVISIBLE (-2900 2300);
FORCEPROP 1 LAST PATH I229
J 0
(-3227 2425);
DISPLAY 0.872340 (-3227 2425);
PAINT GREEN (-3227 2425);
DISPLAY INVISIBLE (-3227 2425);
FORCEADD TAP..1
R 2
(-7650 3300);
FORCEPROP 3 LASTPIN (-7600 3300) SIG_NAME M_H_CPU1_SB_CB<2>
J 0
(-7590 3310);
DISPLAY 0.659574 (-7590 3310);
PAINT MONO (-7590 3310);
DISPLAY INVISIBLE (-7590 3310);
FORCEPROP 1 LASTPIN (-7600 3300) BN 2
J 2
(-7588 3308);
DISPLAY 0.489362 (-7588 3308);
PAINT GREEN (-7588 3308);
FORCEPROP 2 LAST CDS_LIB mstr_standard
J 0
(-7650 3300);
DISPLAY 0.723404 (-7650 3300);
PAINT MONO (-7650 3300);
DISPLAY INVISIBLE (-7650 3300);
FORCEPROP 1 LAST BODY_TYPE PLUMBING
J 2
(-7650 3350);
DISPLAY 0.872340 (-7650 3350);
PAINT GREEN (-7650 3350);
DISPLAY INVISIBLE (-7650 3350);
FORCEPROP 1 LAST HDL_TAP TRUE
J 2
(-7975 3175);
DISPLAY 0.872340 (-7975 3175);
DISPLAY INVISIBLE (-7975 3175);
FORCEPROP 1 LAST PATH I23
J 2
(-7648 3300);
DISPLAY 0.872340 (-7648 3300);
PAINT GREEN (-7648 3300);
DISPLAY INVISIBLE (-7648 3300);
FORCEADD TAP..1
(-3425 3175);
FORCEPROP 3 LASTPIN (-3475 3175) SIG_NAME M_H_CPU1_SB_DQS_DP<7>
J 0
(-3465 3185);
DISPLAY 0.659574 (-3465 3185);
PAINT MONO (-3465 3185);
DISPLAY INVISIBLE (-3465 3185);
FORCEPROP 1 LASTPIN (-3475 3175) BN 7
J 0
(-3487 3183);
DISPLAY 0.489362 (-3487 3183);
PAINT GREEN (-3487 3183);
FORCEPROP 2 LAST CDS_LIB mstr_standard
J 0
(-3425 3175);
DISPLAY 0.723404 (-3425 3175);
PAINT MONO (-3425 3175);
DISPLAY INVISIBLE (-3425 3175);
FORCEPROP 1 LAST BODY_TYPE PLUMBING
J 0
(-3425 3225);
DISPLAY 0.872340 (-3425 3225);
PAINT GREEN (-3425 3225);
DISPLAY INVISIBLE (-3425 3225);
FORCEPROP 1 LAST HDL_TAP TRUE
J 0
(-3100 3050);
DISPLAY 0.872340 (-3100 3050);
DISPLAY INVISIBLE (-3100 3050);
FORCEPROP 1 LAST PATH I230
J 0
(-3427 3175);
DISPLAY 0.872340 (-3427 3175);
PAINT GREEN (-3427 3175);
DISPLAY INVISIBLE (-3427 3175);
FORCEADD TAP..1
(-3425 3075);
FORCEPROP 3 LASTPIN (-3475 3075) SIG_NAME M_H_CPU1_SB_DQS_DP<6>
J 0
(-3465 3085);
DISPLAY 0.659574 (-3465 3085);
PAINT MONO (-3465 3085);
DISPLAY INVISIBLE (-3465 3085);
FORCEPROP 1 LASTPIN (-3475 3075) BN 6
J 0
(-3487 3083);
DISPLAY 0.489362 (-3487 3083);
PAINT GREEN (-3487 3083);
FORCEPROP 2 LAST CDS_LIB mstr_standard
J 0
(-3425 3075);
DISPLAY 0.723404 (-3425 3075);
PAINT MONO (-3425 3075);
DISPLAY INVISIBLE (-3425 3075);
FORCEPROP 1 LAST BODY_TYPE PLUMBING
J 0
(-3425 3125);
DISPLAY 0.872340 (-3425 3125);
PAINT GREEN (-3425 3125);
DISPLAY INVISIBLE (-3425 3125);
FORCEPROP 1 LAST HDL_TAP TRUE
J 0
(-3100 2950);
DISPLAY 0.872340 (-3100 2950);
DISPLAY INVISIBLE (-3100 2950);
FORCEPROP 1 LAST PATH I231
J 0
(-3427 3075);
DISPLAY 0.872340 (-3427 3075);
PAINT GREEN (-3427 3075);
DISPLAY INVISIBLE (-3427 3075);
FORCEADD TAP..1
(-3425 2975);
FORCEPROP 3 LASTPIN (-3475 2975) SIG_NAME M_H_CPU1_SB_DQS_DP<5>
J 0
(-3465 2985);
DISPLAY 0.659574 (-3465 2985);
PAINT MONO (-3465 2985);
DISPLAY INVISIBLE (-3465 2985);
FORCEPROP 1 LASTPIN (-3475 2975) BN 5
J 0
(-3487 2983);
DISPLAY 0.489362 (-3487 2983);
PAINT GREEN (-3487 2983);
FORCEPROP 2 LAST CDS_LIB mstr_standard
J 0
(-3425 2975);
DISPLAY 0.723404 (-3425 2975);
PAINT MONO (-3425 2975);
DISPLAY INVISIBLE (-3425 2975);
FORCEPROP 1 LAST BODY_TYPE PLUMBING
J 0
(-3425 3025);
DISPLAY 0.872340 (-3425 3025);
PAINT GREEN (-3425 3025);
DISPLAY INVISIBLE (-3425 3025);
FORCEPROP 1 LAST HDL_TAP TRUE
J 0
(-3100 2850);
DISPLAY 0.872340 (-3100 2850);
DISPLAY INVISIBLE (-3100 2850);
FORCEPROP 1 LAST PATH I232
J 0
(-3427 2975);
DISPLAY 0.872340 (-3427 2975);
PAINT GREEN (-3427 2975);
DISPLAY INVISIBLE (-3427 2975);
FORCEADD TAP..1
(-3425 2875);
FORCEPROP 3 LASTPIN (-3475 2875) SIG_NAME M_H_CPU1_SB_DQS_DP<4>
J 0
(-3465 2885);
DISPLAY 0.659574 (-3465 2885);
PAINT MONO (-3465 2885);
DISPLAY INVISIBLE (-3465 2885);
FORCEPROP 1 LASTPIN (-3475 2875) BN 4
J 0
(-3487 2883);
DISPLAY 0.489362 (-3487 2883);
PAINT GREEN (-3487 2883);
FORCEPROP 2 LAST CDS_LIB mstr_standard
J 0
(-3425 2875);
DISPLAY 0.723404 (-3425 2875);
PAINT MONO (-3425 2875);
DISPLAY INVISIBLE (-3425 2875);
FORCEPROP 1 LAST BODY_TYPE PLUMBING
J 0
(-3425 2925);
DISPLAY 0.872340 (-3425 2925);
PAINT GREEN (-3425 2925);
DISPLAY INVISIBLE (-3425 2925);
FORCEPROP 1 LAST HDL_TAP TRUE
J 0
(-3100 2750);
DISPLAY 0.872340 (-3100 2750);
DISPLAY INVISIBLE (-3100 2750);
FORCEPROP 1 LAST PATH I233
J 0
(-3427 2875);
DISPLAY 0.872340 (-3427 2875);
PAINT GREEN (-3427 2875);
DISPLAY INVISIBLE (-3427 2875);
FORCEADD TAP..1
(-3425 2775);
FORCEPROP 3 LASTPIN (-3475 2775) SIG_NAME M_H_CPU1_SB_DQS_DP<3>
J 0
(-3465 2785);
DISPLAY 0.659574 (-3465 2785);
PAINT MONO (-3465 2785);
DISPLAY INVISIBLE (-3465 2785);
FORCEPROP 1 LASTPIN (-3475 2775) BN 3
J 0
(-3487 2783);
DISPLAY 0.489362 (-3487 2783);
PAINT GREEN (-3487 2783);
FORCEPROP 2 LAST CDS_LIB mstr_standard
J 0
(-3425 2775);
DISPLAY 0.723404 (-3425 2775);
PAINT MONO (-3425 2775);
DISPLAY INVISIBLE (-3425 2775);
FORCEPROP 1 LAST BODY_TYPE PLUMBING
J 0
(-3425 2825);
DISPLAY 0.872340 (-3425 2825);
PAINT GREEN (-3425 2825);
DISPLAY INVISIBLE (-3425 2825);
FORCEPROP 1 LAST HDL_TAP TRUE
J 0
(-3100 2650);
DISPLAY 0.872340 (-3100 2650);
DISPLAY INVISIBLE (-3100 2650);
FORCEPROP 1 LAST PATH I234
J 0
(-3427 2775);
DISPLAY 0.872340 (-3427 2775);
PAINT GREEN (-3427 2775);
DISPLAY INVISIBLE (-3427 2775);
FORCEADD TAP..1
(-3425 2675);
FORCEPROP 3 LASTPIN (-3475 2675) SIG_NAME M_H_CPU1_SB_DQS_DP<2>
J 0
(-3465 2685);
DISPLAY 0.659574 (-3465 2685);
PAINT MONO (-3465 2685);
DISPLAY INVISIBLE (-3465 2685);
FORCEPROP 1 LASTPIN (-3475 2675) BN 2
J 0
(-3487 2683);
DISPLAY 0.489362 (-3487 2683);
PAINT GREEN (-3487 2683);
FORCEPROP 2 LAST CDS_LIB mstr_standard
J 0
(-3425 2675);
DISPLAY 0.723404 (-3425 2675);
PAINT MONO (-3425 2675);
DISPLAY INVISIBLE (-3425 2675);
FORCEPROP 1 LAST BODY_TYPE PLUMBING
J 0
(-3425 2725);
DISPLAY 0.872340 (-3425 2725);
PAINT GREEN (-3425 2725);
DISPLAY INVISIBLE (-3425 2725);
FORCEPROP 1 LAST HDL_TAP TRUE
J 0
(-3100 2550);
DISPLAY 0.872340 (-3100 2550);
DISPLAY INVISIBLE (-3100 2550);
FORCEPROP 1 LAST PATH I235
J 0
(-3427 2675);
DISPLAY 0.872340 (-3427 2675);
PAINT GREEN (-3427 2675);
DISPLAY INVISIBLE (-3427 2675);
FORCEADD TAP..1
(-3425 2575);
FORCEPROP 3 LASTPIN (-3475 2575) SIG_NAME M_H_CPU1_SB_DQS_DP<1>
J 0
(-3465 2585);
DISPLAY 0.659574 (-3465 2585);
PAINT MONO (-3465 2585);
DISPLAY INVISIBLE (-3465 2585);
FORCEPROP 1 LASTPIN (-3475 2575) BN 1
J 0
(-3487 2583);
DISPLAY 0.489362 (-3487 2583);
PAINT GREEN (-3487 2583);
FORCEPROP 2 LAST CDS_LIB mstr_standard
J 0
(-3425 2575);
DISPLAY 0.723404 (-3425 2575);
PAINT MONO (-3425 2575);
DISPLAY INVISIBLE (-3425 2575);
FORCEPROP 1 LAST BODY_TYPE PLUMBING
J 0
(-3425 2625);
DISPLAY 0.872340 (-3425 2625);
PAINT GREEN (-3425 2625);
DISPLAY INVISIBLE (-3425 2625);
FORCEPROP 1 LAST HDL_TAP TRUE
J 0
(-3100 2450);
DISPLAY 0.872340 (-3100 2450);
DISPLAY INVISIBLE (-3100 2450);
FORCEPROP 1 LAST PATH I236
J 0
(-3427 2575);
DISPLAY 0.872340 (-3427 2575);
PAINT GREEN (-3427 2575);
DISPLAY INVISIBLE (-3427 2575);
FORCEADD TAP..1
(-3425 2475);
FORCEPROP 3 LASTPIN (-3475 2475) SIG_NAME M_H_CPU1_SB_DQS_DP<0>
J 0
(-3465 2485);
DISPLAY 0.659574 (-3465 2485);
PAINT MONO (-3465 2485);
DISPLAY INVISIBLE (-3465 2485);
FORCEPROP 1 LASTPIN (-3475 2475) BN 0
J 0
(-3487 2483);
DISPLAY 0.489362 (-3487 2483);
PAINT GREEN (-3487 2483);
FORCEPROP 2 LAST CDS_LIB mstr_standard
J 0
(-3425 2475);
DISPLAY 0.723404 (-3425 2475);
PAINT MONO (-3425 2475);
DISPLAY INVISIBLE (-3425 2475);
FORCEPROP 1 LAST BODY_TYPE PLUMBING
J 0
(-3425 2525);
DISPLAY 0.872340 (-3425 2525);
PAINT GREEN (-3425 2525);
DISPLAY INVISIBLE (-3425 2525);
FORCEPROP 1 LAST HDL_TAP TRUE
J 0
(-3100 2350);
DISPLAY 0.872340 (-3100 2350);
DISPLAY INVISIBLE (-3100 2350);
FORCEPROP 1 LAST PATH I237
J 0
(-3427 2475);
DISPLAY 0.872340 (-3427 2475);
PAINT GREEN (-3427 2475);
DISPLAY INVISIBLE (-3427 2475);
FORCEADD SCONN288_DDR506112002KQ..2
(-4375 3425);
FORCEPROP 1 LAST LOCATION J27
J 0
(-4975 4750);
DISPLAY 0.468085 (-4975 4750);
PAINT SKYBLUE (-4975 4750);
FORCEPROP 0 LAST $SEC 2
J 0
(-4825 4900);
DISPLAY 0.680851 (-4825 4900);
PAINT MONO (-4825 4900);
DISPLAY INVISIBLE (-4825 4900);
FORCEPROP 0 LAST CDS_SEC 2
J 0
(-4825 4900);
DISPLAY 1.021277 (-4825 4900);
DISPLAY INVISIBLE (-4825 4900);
FORCEPROP 0 LASTPIN (-3625 3475) $PN 12
J 0
(-3615 3485);
DISPLAY 0.680851 (-3615 3485);
PAINT MONO (-3615 3485);
FORCEPROP 0 LASTPIN (-3625 3525) $PN 11
J 0
(-3615 3535);
DISPLAY 0.680851 (-3615 3535);
PAINT MONO (-3615 3535);
FORCEPROP 0 LASTPIN (-3625 2425) $PN 105
J 0
(-3615 2435);
DISPLAY 0.680851 (-3615 2435);
PAINT MONO (-3615 2435);
FORCEPROP 0 LASTPIN (-3625 2475) $PN 104
J 0
(-3615 2485);
DISPLAY 0.680851 (-3615 2485);
PAINT MONO (-3615 2485);
FORCEPROP 0 LASTPIN (-3625 3575) $PN 23
J 0
(-3615 3585);
DISPLAY 0.680851 (-3615 3585);
PAINT MONO (-3615 3585);
FORCEPROP 0 LASTPIN (-3625 3625) $PN 22
J 0
(-3615 3635);
DISPLAY 0.680851 (-3615 3635);
PAINT MONO (-3615 3635);
FORCEPROP 0 LASTPIN (-3625 2525) $PN 116
J 0
(-3615 2535);
DISPLAY 0.680851 (-3615 2535);
PAINT MONO (-3615 2535);
FORCEPROP 0 LASTPIN (-3625 2575) $PN 115
J 0
(-3615 2585);
DISPLAY 0.680851 (-3615 2585);
PAINT MONO (-3615 2585);
FORCEPROP 0 LASTPIN (-3625 3675) $PN 34
J 0
(-3615 3685);
DISPLAY 0.680851 (-3615 3685);
PAINT MONO (-3615 3685);
FORCEPROP 0 LASTPIN (-3625 3725) $PN 33
J 0
(-3615 3735);
DISPLAY 0.680851 (-3615 3735);
PAINT MONO (-3615 3735);
FORCEPROP 0 LASTPIN (-3625 2625) $PN 127
J 0
(-3615 2635);
DISPLAY 0.680851 (-3615 2635);
PAINT MONO (-3615 2635);
FORCEPROP 0 LASTPIN (-3625 2675) $PN 126
J 0
(-3615 2685);
DISPLAY 0.680851 (-3615 2685);
PAINT MONO (-3615 2685);
FORCEPROP 0 LASTPIN (-3625 3775) $PN 45
J 0
(-3615 3785);
DISPLAY 0.680851 (-3615 3785);
PAINT MONO (-3615 3785);
FORCEPROP 0 LASTPIN (-3625 3825) $PN 44
J 0
(-3615 3835);
DISPLAY 0.680851 (-3615 3835);
PAINT MONO (-3615 3835);
FORCEPROP 0 LASTPIN (-3625 2725) $PN 138
J 0
(-3615 2735);
DISPLAY 0.680851 (-3615 2735);
PAINT MONO (-3615 2735);
FORCEPROP 0 LASTPIN (-3625 2775) $PN 137
J 0
(-3615 2785);
DISPLAY 0.680851 (-3615 2785);
PAINT MONO (-3615 2785);
FORCEPROP 0 LASTPIN (-3625 3875) $PN 56
J 0
(-3615 3885);
DISPLAY 0.680851 (-3615 3885);
PAINT MONO (-3615 3885);
FORCEPROP 0 LASTPIN (-3625 3925) $PN 55
J 0
(-3615 3935);
DISPLAY 0.680851 (-3615 3935);
PAINT MONO (-3615 3935);
FORCEPROP 0 LASTPIN (-3625 2825) $PN 238
J 0
(-3615 2835);
DISPLAY 0.680851 (-3615 2835);
PAINT MONO (-3615 2835);
FORCEPROP 0 LASTPIN (-3625 2875) $PN 239
J 0
(-3615 2885);
DISPLAY 0.680851 (-3615 2885);
PAINT MONO (-3615 2885);
FORCEPROP 0 LASTPIN (-3625 3975) $PN 156
J 0
(-3615 3985);
DISPLAY 0.680851 (-3615 3985);
PAINT MONO (-3615 3985);
FORCEPROP 0 LASTPIN (-3625 4025) $PN 157
J 0
(-3615 4035);
DISPLAY 0.680851 (-3615 4035);
PAINT MONO (-3615 4035);
FORCEPROP 0 LASTPIN (-3625 2925) $PN 249
J 0
(-3615 2935);
DISPLAY 0.680851 (-3615 2935);
PAINT MONO (-3615 2935);
FORCEPROP 0 LASTPIN (-3625 2975) $PN 250
J 0
(-3615 2985);
DISPLAY 0.680851 (-3615 2985);
PAINT MONO (-3615 2985);
FORCEPROP 0 LASTPIN (-3625 4075) $PN 167
J 0
(-3615 4085);
DISPLAY 0.680851 (-3615 4085);
PAINT MONO (-3615 4085);
FORCEPROP 0 LASTPIN (-3625 4125) $PN 168
J 0
(-3615 4135);
DISPLAY 0.680851 (-3615 4135);
PAINT MONO (-3615 4135);
FORCEPROP 0 LASTPIN (-3625 3025) $PN 260
J 0
(-3615 3035);
DISPLAY 0.680851 (-3615 3035);
PAINT MONO (-3615 3035);
FORCEPROP 0 LASTPIN (-3625 3075) $PN 261
J 0
(-3615 3085);
DISPLAY 0.680851 (-3615 3085);
PAINT MONO (-3615 3085);
FORCEPROP 0 LASTPIN (-3625 4175) $PN 178
J 0
(-3615 4185);
DISPLAY 0.680851 (-3615 4185);
PAINT MONO (-3615 4185);
FORCEPROP 0 LASTPIN (-3625 4225) $PN 179
J 0
(-3615 4235);
DISPLAY 0.680851 (-3615 4235);
PAINT MONO (-3615 4235);
FORCEPROP 0 LASTPIN (-3625 3125) $PN 271
J 0
(-3615 3135);
DISPLAY 0.680851 (-3615 3135);
PAINT MONO (-3615 3135);
FORCEPROP 0 LASTPIN (-3625 3175) $PN 272
J 0
(-3615 3185);
DISPLAY 0.680851 (-3615 3185);
PAINT MONO (-3615 3185);
FORCEPROP 0 LASTPIN (-3625 4275) $PN 189
J 0
(-3615 4285);
DISPLAY 0.680851 (-3615 4285);
PAINT MONO (-3615 4285);
FORCEPROP 0 LASTPIN (-3625 4325) $PN 190
J 0
(-3615 4335);
DISPLAY 0.680851 (-3615 4335);
PAINT MONO (-3615 4335);
FORCEPROP 0 LASTPIN (-3625 3225) $PN 282
J 0
(-3615 3235);
DISPLAY 0.680851 (-3615 3235);
PAINT MONO (-3615 3235);
FORCEPROP 0 LASTPIN (-3625 3275) $PN 283
J 0
(-3615 3285);
DISPLAY 0.680851 (-3615 3285);
PAINT MONO (-3615 3285);
FORCEPROP 0 LASTPIN (-3625 4375) $PN 200
J 0
(-3615 4385);
DISPLAY 0.680851 (-3615 4385);
PAINT MONO (-3615 4385);
FORCEPROP 0 LASTPIN (-3625 4425) $PN 201
J 0
(-3615 4435);
DISPLAY 0.680851 (-3615 4435);
PAINT MONO (-3615 4435);
FORCEPROP 0 LASTPIN (-3625 3325) $PN 94
J 0
(-3615 3335);
DISPLAY 0.680851 (-3615 3335);
PAINT MONO (-3615 3335);
FORCEPROP 0 LASTPIN (-3625 3375) $PN 93
J 0
(-3615 3385);
DISPLAY 0.680851 (-3615 3385);
PAINT MONO (-3615 3385);
FORCEPROP 2 LAST PART_TYPE SMLF
J 0
(-4825 4850);
DISPLAY 1.021277 (-4825 4850);
FORCEPROP 1 LAST MATERIAL IO
J 0
(-4975 4600);
DISPLAY 0.468085 (-4975 4600);
PAINT SKYBLUE (-4975 4600);
FORCEPROP 1 LAST PART_NUMBER DFHST8FS479
J 0
(-4975 4675);
DISPLAY 0.468085 (-4975 4675);
PAINT SKYBLUE (-4975 4675);
FORCEPROP 2 LAST VALUE SCONN288_DDR506112002KQ
J 0
(-4825 4800);
DISPLAY 0.489362 (-4825 4800);
PAINT SKYBLUE (-4825 4800);
FORCEPROP 1 LAST CDS_LMAN_SYM_OUTLINE -600,1150,600,-1150
J 0
(-4375 3425);
DISPLAY 0.468085 (-4375 3425);
PAINT GREEN (-4375 3425);
DISPLAY INVISIBLE (-4375 3425);
FORCEPROP 1 LAST PATH I238
J 0
(-4375 3425);
DISPLAY 0.723404 (-4375 3425);
PAINT GREEN (-4375 3425);
DISPLAY INVISIBLE (-4375 3425);
FORCEPROP 1 LAST NEEDS_NO_SIZE TRUE
J 0
(-4375 3425);
DISPLAY 0.723404 (-4375 3425);
PAINT GREEN (-4375 3425);
DISPLAY INVISIBLE (-4375 3425);
FORCEPROP 2 LAST CDS_LIB pure_quanta
J 0
(-4375 3425);
DISPLAY INVISIBLE (-4375 3425);
FORCEADD GND..1
(-2825 5525);
FORCEPROP 3 LASTPIN (-2825 5575) SIG_NAME GND\g
J 0
(-2815 5585);
DISPLAY 0.659574 (-2815 5585);
PAINT MONO (-2815 5585);
DISPLAY INVISIBLE (-2815 5585);
FORCEPROP 2 LAST CDS_LIB pure_quanta_power
J 0
(-2825 5525);
DISPLAY INVISIBLE (-2825 5525);
FORCEPROP 2 LAST BOM_COST MEM
J 0
(-2800 5650);
DISPLAY 0.659574 (-2800 5650);
DISPLAY INVISIBLE (-2800 5650);
FORCEPROP 1 LAST SIZE 1B
J 0
(-2750 5475);
DISPLAY 0.723404 (-2750 5475);
PAINT GREEN (-2750 5475);
DISPLAY INVISIBLE (-2750 5475);
FORCEPROP 1 LAST PATH I239
J 0
(-2750 5525);
DISPLAY 0.872340 (-2750 5525);
PAINT AQUA (-2750 5525);
DISPLAY INVISIBLE (-2750 5525);
FORCEPROP 2 LAST ROOM MEM_EFGH_DECOUPLING_CAPS
J 0
(-2800 5600);
DISPLAY 0.659574 (-2800 5600);
PAINT RED (-2800 5600);
DISPLAY INVISIBLE (-2800 5600);
FORCEPROP 1 LAST HDL_POWER GND
J 0
(-2825 5675);
DISPLAY 0.723404 (-2825 5675);
PAINT GREEN (-2825 5675);
DISPLAY INVISIBLE (-2825 5675);
FORCEADD TAP..1
R 2
(-7650 3350);
FORCEPROP 3 LASTPIN (-7600 3350) SIG_NAME M_H_CPU1_SB_CB<3>
J 0
(-7590 3360);
DISPLAY 0.659574 (-7590 3360);
PAINT MONO (-7590 3360);
DISPLAY INVISIBLE (-7590 3360);
FORCEPROP 1 LASTPIN (-7600 3350) BN 3
J 2
(-7588 3358);
DISPLAY 0.489362 (-7588 3358);
PAINT GREEN (-7588 3358);
FORCEPROP 2 LAST CDS_LIB mstr_standard
J 0
(-7650 3350);
DISPLAY 0.723404 (-7650 3350);
PAINT MONO (-7650 3350);
DISPLAY INVISIBLE (-7650 3350);
FORCEPROP 1 LAST BODY_TYPE PLUMBING
J 2
(-7650 3400);
DISPLAY 0.872340 (-7650 3400);
PAINT GREEN (-7650 3400);
DISPLAY INVISIBLE (-7650 3400);
FORCEPROP 1 LAST HDL_TAP TRUE
J 2
(-7975 3225);
DISPLAY 0.872340 (-7975 3225);
DISPLAY INVISIBLE (-7975 3225);
FORCEPROP 1 LAST PATH I24
J 2
(-7648 3350);
DISPLAY 0.872340 (-7648 3350);
PAINT GREEN (-7648 3350);
DISPLAY INVISIBLE (-7648 3350);
FORCEADD Q_CAP..1
R 2
(-2825 5875);
FORCEPROP 1 LAST LOCATION C532
J 2
(-2875 5975);
DISPLAY 0.489362 (-2875 5975);
PAINT SKYBLUE (-2875 5975);
FORCEPROP 0 LAST $SEC 1
J 0
(-2875 6025);
DISPLAY 0.680851 (-2875 6025);
PAINT MONO (-2875 6025);
DISPLAY INVISIBLE (-2875 6025);
FORCEPROP 0 LAST CDS_SEC 1
J 0
(-2875 6025);
DISPLAY 0.680851 (-2875 6025);
DISPLAY INVISIBLE (-2875 6025);
FORCEPROP 1 LASTPIN (-2825 5975) $PN 1
J 2
(-2835 5955);
DISPLAY 0.489362 (-2835 5955);
PAINT MONO (-2835 5955);
FORCEPROP 1 LASTPIN (-2825 5775) $PN 2
J 2
(-2835 5755);
DISPLAY 0.489362 (-2835 5755);
PAINT MONO (-2835 5755);
FORCEPROP 1 LAST MATERIAL X6S
J 2
(-2875 5775);
DISPLAY 0.489362 (-2875 5775);
PAINT SKYBLUE (-2875 5775);
FORCEPROP 1 LAST TOLERANCE 10%
J 2
(-2875 5825);
DISPLAY 0.489362 (-2875 5825);
PAINT SKYBLUE (-2875 5825);
FORCEPROP 1 LAST VALUE 10UF
J 2
(-2875 5925);
DISPLAY 0.489362 (-2875 5925);
PAINT SKYBLUE (-2875 5925);
FORCEPROP 1 LAST PART_NUMBER CH6104KEA00
J 2
(-2875 5725);
DISPLAY 0.489362 (-2875 5725);
PAINT SKYBLUE (-2875 5725);
FORCEPROP 1 LAST VOLTAGE 25V
J 2
(-2875 5875);
DISPLAY 0.489362 (-2875 5875);
PAINT SKYBLUE (-2875 5875);
FORCEPROP 1 LAST PACK_TYPE C0805
J 2
(-2875 5675);
DISPLAY 0.489362 (-2875 5675);
PAINT SKYBLUE (-2875 5675);
FORCEPROP 0 LAST BOM_COST MEM
J 2
(-2880 6020);
DISPLAY 0.595745 (-2880 6020);
PAINT MONO (-2880 6020);
DISPLAY INVISIBLE (-2880 6020);
FORCEPROP 2 LAST CDS_LIB pure_quanta
J 0
(-2825 5875);
DISPLAY INVISIBLE (-2825 5875);
FORCEPROP 1 LAST PATH I240
J 2
(-2875 6025);
DISPLAY 0.978723 (-2875 6025);
PAINT WHITE (-2875 6025);
DISPLAY INVISIBLE (-2875 6025);
FORCEPROP 0 LAST ROOM MEM_CH_A_CPU0_DIMM1
J 2
(-2880 6020);
DISPLAY 0.595745 (-2880 6020);
PAINT RED (-2880 6020);
DISPLAY INVISIBLE (-2880 6020);
FORCEADD Q_CAP..1
R 2
(-2250 5875);
FORCEPROP 1 LAST LOCATION C533
J 2
(-2300 5975);
DISPLAY 0.489362 (-2300 5975);
PAINT SKYBLUE (-2300 5975);
FORCEPROP 0 LAST $SEC 1
J 0
(-2300 6025);
DISPLAY 0.680851 (-2300 6025);
PAINT MONO (-2300 6025);
DISPLAY INVISIBLE (-2300 6025);
FORCEPROP 0 LAST CDS_SEC 1
J 0
(-2300 6025);
DISPLAY 0.680851 (-2300 6025);
DISPLAY INVISIBLE (-2300 6025);
FORCEPROP 1 LASTPIN (-2250 5975) $PN 1
J 2
(-2260 5955);
DISPLAY 0.489362 (-2260 5955);
PAINT MONO (-2260 5955);
FORCEPROP 1 LASTPIN (-2250 5775) $PN 2
J 2
(-2260 5755);
DISPLAY 0.489362 (-2260 5755);
PAINT MONO (-2260 5755);
FORCEPROP 1 LAST MATERIAL X6S
J 2
(-2300 5775);
DISPLAY 0.489362 (-2300 5775);
PAINT SKYBLUE (-2300 5775);
FORCEPROP 1 LAST TOLERANCE 10%
J 2
(-2300 5825);
DISPLAY 0.489362 (-2300 5825);
PAINT SKYBLUE (-2300 5825);
FORCEPROP 1 LAST VALUE 10UF
J 2
(-2300 5925);
DISPLAY 0.489362 (-2300 5925);
PAINT SKYBLUE (-2300 5925);
FORCEPROP 1 LAST VOLTAGE 25V
J 2
(-2300 5875);
DISPLAY 0.489362 (-2300 5875);
PAINT SKYBLUE (-2300 5875);
FORCEPROP 1 LAST PACK_TYPE C0805
J 2
(-2300 5675);
DISPLAY 0.489362 (-2300 5675);
PAINT SKYBLUE (-2300 5675);
FORCEPROP 1 LAST PART_NUMBER CH6104KEA00
J 2
(-2300 5725);
DISPLAY 0.489362 (-2300 5725);
PAINT SKYBLUE (-2300 5725);
FORCEPROP 0 LAST BOM_COST MEM
J 2
(-2305 6020);
DISPLAY 0.595745 (-2305 6020);
PAINT MONO (-2305 6020);
DISPLAY INVISIBLE (-2305 6020);
FORCEPROP 2 LAST CDS_LIB pure_quanta
J 0
(-2250 5875);
DISPLAY INVISIBLE (-2250 5875);
FORCEPROP 1 LAST PATH I241
J 2
(-2300 6025);
DISPLAY 0.978723 (-2300 6025);
PAINT WHITE (-2300 6025);
DISPLAY INVISIBLE (-2300 6025);
FORCEPROP 0 LAST ROOM MEM_CH_A_CPU0_DIMM1
J 2
(-2305 6020);
DISPLAY 0.595745 (-2305 6020);
PAINT RED (-2305 6020);
DISPLAY INVISIBLE (-2305 6020);
FORCEADD UNIVERSAL_POWER..1
(-2825 6200);
FORCEPROP 3 LASTPIN (-2825 6150) SIG_NAME P12V_MEM_1\g
J 0
(-2815 6160);
DISPLAY 0.659574 (-2815 6160);
PAINT MONO (-2815 6160);
DISPLAY INVISIBLE (-2815 6160);
FORCEPROP 1 LAST HDL_POWER P12V_MEM_1
J 1
(-2825 6250);
DISPLAY 0.489362 (-2825 6250);
PAINT GREEN (-2825 6250);
FORCEPROP 2 LAST CDS_LIB pure_quanta_power
J 0
(-2825 6200);
DISPLAY INVISIBLE (-2825 6200);
FORCEPROP 1 LAST PATH I242
J 0
(-2775 6225);
DISPLAY 0.872340 (-2775 6225);
PAINT AQUA (-2775 6225);
DISPLAY INVISIBLE (-2775 6225);
FORCEADD OFFPAGE..1
(-8275 2700);
FORCEPROP 2 LAST $XR5 108 
J 0
(-9157 2700);
DISPLAY 0.638298 (-9157 2700);
PAINT MONO (-9157 2700);
FORCEPROP 2 LAST $XR4 107 
J 0
(-9037 2700);
DISPLAY 0.638298 (-9037 2700);
PAINT MONO (-9037 2700);
FORCEPROP 2 LAST $XR3 106 
J 0
(-8917 2700);
DISPLAY 0.638298 (-8917 2700);
PAINT MONO (-8917 2700);
FORCEPROP 2 LAST $XR2 105 
J 0
(-8797 2700);
DISPLAY 0.638298 (-8797 2700);
PAINT MONO (-8797 2700);
FORCEPROP 2 LAST $XR1 103 
J 0
(-8677 2700);
DISPLAY 0.638298 (-8677 2700);
PAINT MONO (-8677 2700);
FORCEPROP 2 LAST $XR0 136 
J 0
(-8557 2700);
DISPLAY 0.638298 (-8557 2700);
PAINT MONO (-8557 2700);
FORCEPROP 2 LAST PATH I243
J 0
(-8550 2750);
DISPLAY 0.680851 (-8550 2750);
DISPLAY INVISIBLE (-8550 2750);
FORCEPROP 1 LAST COMMENT_BODY TRUE
J 0
(-8150 2600);
DISPLAY 0.872340 (-8150 2600);
PAINT GREEN (-8150 2600);
DISPLAY INVISIBLE (-8150 2600);
FORCEPROP 1 LAST OFFPAGE TRUE
J 0
(-7950 2575);
DISPLAY 0.872340 (-7950 2575);
PAINT GREEN (-7950 2575);
DISPLAY INVISIBLE (-7950 2575);
FORCEPROP 2 LAST CDS_LIB mstr_standard
J 0
(-8275 2700);
DISPLAY 0.808511 (-8275 2700);
DISPLAY INVISIBLE (-8275 2700);
FORCEADD Q_RES..1
(-7700 2700);
FORCEPROP 1 LAST $LOCATION R1587
J 0
(-7750 2725);
DISPLAY 0.510638 (-7750 2725);
PAINT SKYBLUE (-7750 2725);
FORCEPROP 0 LAST CDS_LOCATION R1587
J 0
(-7750 2800);
DISPLAY 0.680851 (-7750 2800);
DISPLAY INVISIBLE (-7750 2800);
FORCEPROP 0 LAST $SEC 1
J 0
(-7750 2800);
DISPLAY 0.680851 (-7750 2800);
PAINT MONO (-7750 2800);
DISPLAY INVISIBLE (-7750 2800);
FORCEPROP 0 LAST CDS_SEC 1
J 0
(-7750 2800);
DISPLAY 0.680851 (-7750 2800);
DISPLAY INVISIBLE (-7750 2800);
FORCEPROP 1 LASTPIN (-7800 2700) $PN 1
J 0
(-7788 2712);
DISPLAY 0.787234 (-7788 2712);
PAINT MONO (-7788 2712);
FORCEPROP 1 LASTPIN (-7600 2700) $PN 2
J 0
(-7638 2712);
DISPLAY 0.787234 (-7638 2712);
PAINT MONO (-7638 2712);
FORCEPROP 1 LAST VALUE 49.9
J 2
(-7525 2750);
DISPLAY 0.510638 (-7525 2750);
PAINT SKYBLUE (-7525 2750);
FORCEPROP 2 LAST CDS_LIB pure_quanta
J 0
(-7700 2700);
DISPLAY INVISIBLE (-7700 2700);
FORCEPROP 1 LAST PATH I244
J 0
(-7750 2850);
DISPLAY 0.978723 (-7750 2850);
PAINT WHITE (-7750 2850);
DISPLAY INVISIBLE (-7750 2850);
FORCEPROP 1 LAST MATERIAL CHIP
J 0
(-7700 2550);
DISPLAY 0.978723 (-7700 2550);
DISPLAY INVISIBLE (-7700 2550);
FORCEPROP 1 LAST PACK_TYPE 0402LF
J 0
(-7450 2550);
DISPLAY 0.978723 (-7450 2550);
DISPLAY INVISIBLE (-7450 2550);
FORCEPROP 1 LAST WATTAGE 1/16W
J 2
(-7725 2550);
DISPLAY 0.978723 (-7725 2550);
DISPLAY INVISIBLE (-7725 2550);
FORCEPROP 1 LAST TOLERANCE 1%
J 0
(-7700 2600);
DISPLAY 0.978723 (-7700 2600);
DISPLAY INVISIBLE (-7700 2600);
FORCEPROP 1 LAST PART_NUMBER CS04992FB07
J 0
(-7750 2800);
DISPLAY 0.978723 (-7750 2800);
DISPLAY INVISIBLE (-7750 2800);
FORCEADD TAP..1
R 2
(-7650 3250);
FORCEPROP 3 LASTPIN (-7600 3250) SIG_NAME M_H_CPU1_SB_CB<1>
J 0
(-7590 3260);
DISPLAY 0.659574 (-7590 3260);
PAINT MONO (-7590 3260);
DISPLAY INVISIBLE (-7590 3260);
FORCEPROP 1 LASTPIN (-7600 3250) BN 1
J 2
(-7588 3258);
DISPLAY 0.489362 (-7588 3258);
PAINT GREEN (-7588 3258);
FORCEPROP 2 LAST CDS_LIB mstr_standard
J 0
(-7650 3250);
DISPLAY 0.723404 (-7650 3250);
PAINT MONO (-7650 3250);
DISPLAY INVISIBLE (-7650 3250);
FORCEPROP 1 LAST BODY_TYPE PLUMBING
J 2
(-7650 3300);
DISPLAY 0.872340 (-7650 3300);
PAINT GREEN (-7650 3300);
DISPLAY INVISIBLE (-7650 3300);
FORCEPROP 1 LAST HDL_TAP TRUE
J 2
(-7975 3125);
DISPLAY 0.872340 (-7975 3125);
DISPLAY INVISIBLE (-7975 3125);
FORCEPROP 1 LAST PATH I25
J 2
(-7648 3250);
DISPLAY 0.872340 (-7648 3250);
PAINT GREEN (-7648 3250);
DISPLAY INVISIBLE (-7648 3250);
FORCEADD TAP..1
R 2
(-7650 3200);
FORCEPROP 3 LASTPIN (-7600 3200) SIG_NAME M_H_CPU1_SB_CB<0>
J 0
(-7590 3210);
DISPLAY 0.659574 (-7590 3210);
PAINT MONO (-7590 3210);
DISPLAY INVISIBLE (-7590 3210);
FORCEPROP 1 LASTPIN (-7600 3200) BN 0
J 2
(-7588 3208);
DISPLAY 0.489362 (-7588 3208);
PAINT GREEN (-7588 3208);
FORCEPROP 2 LAST CDS_LIB mstr_standard
J 0
(-7650 3200);
DISPLAY 0.723404 (-7650 3200);
PAINT MONO (-7650 3200);
DISPLAY INVISIBLE (-7650 3200);
FORCEPROP 1 LAST BODY_TYPE PLUMBING
J 2
(-7650 3250);
DISPLAY 0.872340 (-7650 3250);
PAINT GREEN (-7650 3250);
DISPLAY INVISIBLE (-7650 3250);
FORCEPROP 1 LAST HDL_TAP TRUE
J 2
(-7975 3075);
DISPLAY 0.872340 (-7975 3075);
DISPLAY INVISIBLE (-7975 3075);
FORCEPROP 1 LAST PATH I26
J 2
(-7648 3200);
DISPLAY 0.872340 (-7648 3200);
PAINT GREEN (-7648 3200);
DISPLAY INVISIBLE (-7648 3200);
FORCEADD TAP..1
R 2
(-7650 3400);
FORCEPROP 3 LASTPIN (-7600 3400) SIG_NAME M_H_CPU1_SB_CB<4>
J 0
(-7590 3410);
DISPLAY 0.659574 (-7590 3410);
PAINT MONO (-7590 3410);
DISPLAY INVISIBLE (-7590 3410);
FORCEPROP 1 LASTPIN (-7600 3400) BN 4
J 2
(-7588 3408);
DISPLAY 0.489362 (-7588 3408);
PAINT GREEN (-7588 3408);
FORCEPROP 2 LAST CDS_LIB mstr_standard
J 0
(-7650 3400);
DISPLAY 0.723404 (-7650 3400);
PAINT MONO (-7650 3400);
DISPLAY INVISIBLE (-7650 3400);
FORCEPROP 1 LAST BODY_TYPE PLUMBING
J 2
(-7650 3450);
DISPLAY 0.872340 (-7650 3450);
PAINT GREEN (-7650 3450);
DISPLAY INVISIBLE (-7650 3450);
FORCEPROP 1 LAST HDL_TAP TRUE
J 2
(-7975 3275);
DISPLAY 0.872340 (-7975 3275);
DISPLAY INVISIBLE (-7975 3275);
FORCEPROP 1 LAST PATH I27
J 2
(-7648 3400);
DISPLAY 0.872340 (-7648 3400);
PAINT GREEN (-7648 3400);
DISPLAY INVISIBLE (-7648 3400);
FORCEADD TAP..1
R 2
(-7650 3450);
FORCEPROP 3 LASTPIN (-7600 3450) SIG_NAME M_H_CPU1_SB_CB<5>
J 0
(-7590 3460);
DISPLAY 0.659574 (-7590 3460);
PAINT MONO (-7590 3460);
DISPLAY INVISIBLE (-7590 3460);
FORCEPROP 1 LASTPIN (-7600 3450) BN 5
J 2
(-7588 3458);
DISPLAY 0.489362 (-7588 3458);
PAINT GREEN (-7588 3458);
FORCEPROP 2 LAST CDS_LIB mstr_standard
J 0
(-7650 3450);
DISPLAY 0.723404 (-7650 3450);
PAINT MONO (-7650 3450);
DISPLAY INVISIBLE (-7650 3450);
FORCEPROP 1 LAST BODY_TYPE PLUMBING
J 2
(-7650 3500);
DISPLAY 0.872340 (-7650 3500);
PAINT GREEN (-7650 3500);
DISPLAY INVISIBLE (-7650 3500);
FORCEPROP 1 LAST HDL_TAP TRUE
J 2
(-7975 3325);
DISPLAY 0.872340 (-7975 3325);
DISPLAY INVISIBLE (-7975 3325);
FORCEPROP 1 LAST PATH I28
J 2
(-7648 3450);
DISPLAY 0.872340 (-7648 3450);
PAINT GREEN (-7648 3450);
DISPLAY INVISIBLE (-7648 3450);
FORCEADD TAP..1
R 2
(-7650 3500);
FORCEPROP 3 LASTPIN (-7600 3500) SIG_NAME M_H_CPU1_SB_CB<6>
J 0
(-7590 3510);
DISPLAY 0.659574 (-7590 3510);
PAINT MONO (-7590 3510);
DISPLAY INVISIBLE (-7590 3510);
FORCEPROP 1 LASTPIN (-7600 3500) BN 6
J 2
(-7588 3508);
DISPLAY 0.489362 (-7588 3508);
PAINT GREEN (-7588 3508);
FORCEPROP 2 LAST CDS_LIB mstr_standard
J 0
(-7650 3500);
DISPLAY 0.723404 (-7650 3500);
PAINT MONO (-7650 3500);
DISPLAY INVISIBLE (-7650 3500);
FORCEPROP 1 LAST BODY_TYPE PLUMBING
J 2
(-7650 3550);
DISPLAY 0.872340 (-7650 3550);
PAINT GREEN (-7650 3550);
DISPLAY INVISIBLE (-7650 3550);
FORCEPROP 1 LAST HDL_TAP TRUE
J 2
(-7975 3375);
DISPLAY 0.872340 (-7975 3375);
DISPLAY INVISIBLE (-7975 3375);
FORCEPROP 1 LAST PATH I29
J 2
(-7648 3500);
DISPLAY 0.872340 (-7648 3500);
PAINT GREEN (-7648 3500);
DISPLAY INVISIBLE (-7648 3500);
FORCEADD TAP..1
R 2
(-7650 3550);
FORCEPROP 3 LASTPIN (-7600 3550) SIG_NAME M_H_CPU1_SB_CB<7>
J 0
(-7590 3560);
DISPLAY 0.659574 (-7590 3560);
PAINT MONO (-7590 3560);
DISPLAY INVISIBLE (-7590 3560);
FORCEPROP 1 LASTPIN (-7600 3550) BN 7
J 2
(-7588 3558);
DISPLAY 0.489362 (-7588 3558);
PAINT GREEN (-7588 3558);
FORCEPROP 2 LAST CDS_LIB mstr_standard
J 0
(-7650 3550);
DISPLAY 0.723404 (-7650 3550);
PAINT MONO (-7650 3550);
DISPLAY INVISIBLE (-7650 3550);
FORCEPROP 1 LAST BODY_TYPE PLUMBING
J 2
(-7650 3600);
DISPLAY 0.872340 (-7650 3600);
PAINT GREEN (-7650 3600);
DISPLAY INVISIBLE (-7650 3600);
FORCEPROP 1 LAST HDL_TAP TRUE
J 2
(-7975 3425);
DISPLAY 0.872340 (-7975 3425);
DISPLAY INVISIBLE (-7975 3425);
FORCEPROP 1 LAST PATH I30
J 2
(-7648 3550);
DISPLAY 0.872340 (-7648 3550);
PAINT GREEN (-7648 3550);
DISPLAY INVISIBLE (-7648 3550);
FORCEADD TAP..1
R 2
(-7650 3650);
FORCEPROP 3 LASTPIN (-7600 3650) SIG_NAME M_H_CPU1_SA_CB<0>
J 0
(-7590 3660);
DISPLAY 0.659574 (-7590 3660);
PAINT MONO (-7590 3660);
DISPLAY INVISIBLE (-7590 3660);
FORCEPROP 1 LASTPIN (-7600 3650) BN 0
J 2
(-7588 3658);
DISPLAY 0.489362 (-7588 3658);
PAINT GREEN (-7588 3658);
FORCEPROP 2 LAST CDS_LIB mstr_standard
J 0
(-7650 3650);
DISPLAY 0.723404 (-7650 3650);
PAINT MONO (-7650 3650);
DISPLAY INVISIBLE (-7650 3650);
FORCEPROP 1 LAST BODY_TYPE PLUMBING
J 2
(-7650 3700);
DISPLAY 0.872340 (-7650 3700);
PAINT GREEN (-7650 3700);
DISPLAY INVISIBLE (-7650 3700);
FORCEPROP 1 LAST HDL_TAP TRUE
J 2
(-7975 3525);
DISPLAY 0.872340 (-7975 3525);
DISPLAY INVISIBLE (-7975 3525);
FORCEPROP 1 LAST PATH I31
J 2
(-7648 3650);
DISPLAY 0.872340 (-7648 3650);
PAINT GREEN (-7648 3650);
DISPLAY INVISIBLE (-7648 3650);
FORCEADD TAP..1
R 2
(-7650 3700);
FORCEPROP 3 LASTPIN (-7600 3700) SIG_NAME M_H_CPU1_SA_CB<1>
J 0
(-7590 3710);
DISPLAY 0.659574 (-7590 3710);
PAINT MONO (-7590 3710);
DISPLAY INVISIBLE (-7590 3710);
FORCEPROP 1 LASTPIN (-7600 3700) BN 1
J 2
(-7588 3708);
DISPLAY 0.489362 (-7588 3708);
PAINT GREEN (-7588 3708);
FORCEPROP 2 LAST CDS_LIB mstr_standard
J 0
(-7650 3700);
DISPLAY 0.723404 (-7650 3700);
PAINT MONO (-7650 3700);
DISPLAY INVISIBLE (-7650 3700);
FORCEPROP 1 LAST BODY_TYPE PLUMBING
J 2
(-7650 3750);
DISPLAY 0.872340 (-7650 3750);
PAINT GREEN (-7650 3750);
DISPLAY INVISIBLE (-7650 3750);
FORCEPROP 1 LAST HDL_TAP TRUE
J 2
(-7975 3575);
DISPLAY 0.872340 (-7975 3575);
DISPLAY INVISIBLE (-7975 3575);
FORCEPROP 1 LAST PATH I32
J 2
(-7648 3700);
DISPLAY 0.872340 (-7648 3700);
PAINT GREEN (-7648 3700);
DISPLAY INVISIBLE (-7648 3700);
FORCEADD TAP..1
R 2
(-7650 3750);
FORCEPROP 3 LASTPIN (-7600 3750) SIG_NAME M_H_CPU1_SA_CB<2>
J 0
(-7590 3760);
DISPLAY 0.659574 (-7590 3760);
PAINT MONO (-7590 3760);
DISPLAY INVISIBLE (-7590 3760);
FORCEPROP 1 LASTPIN (-7600 3750) BN 2
J 2
(-7588 3758);
DISPLAY 0.489362 (-7588 3758);
PAINT GREEN (-7588 3758);
FORCEPROP 2 LAST CDS_LIB mstr_standard
J 0
(-7650 3750);
DISPLAY 0.723404 (-7650 3750);
PAINT MONO (-7650 3750);
DISPLAY INVISIBLE (-7650 3750);
FORCEPROP 1 LAST BODY_TYPE PLUMBING
J 2
(-7650 3800);
DISPLAY 0.872340 (-7650 3800);
PAINT GREEN (-7650 3800);
DISPLAY INVISIBLE (-7650 3800);
FORCEPROP 1 LAST HDL_TAP TRUE
J 2
(-7975 3625);
DISPLAY 0.872340 (-7975 3625);
DISPLAY INVISIBLE (-7975 3625);
FORCEPROP 1 LAST PATH I33
J 2
(-7648 3750);
DISPLAY 0.872340 (-7648 3750);
PAINT GREEN (-7648 3750);
DISPLAY INVISIBLE (-7648 3750);
FORCEADD TAP..1
R 2
(-7650 3800);
FORCEPROP 3 LASTPIN (-7600 3800) SIG_NAME M_H_CPU1_SA_CB<3>
J 0
(-7590 3810);
DISPLAY 0.659574 (-7590 3810);
PAINT MONO (-7590 3810);
DISPLAY INVISIBLE (-7590 3810);
FORCEPROP 1 LASTPIN (-7600 3800) BN 3
J 2
(-7588 3808);
DISPLAY 0.489362 (-7588 3808);
PAINT GREEN (-7588 3808);
FORCEPROP 2 LAST CDS_LIB mstr_standard
J 0
(-7650 3800);
DISPLAY 0.723404 (-7650 3800);
PAINT MONO (-7650 3800);
DISPLAY INVISIBLE (-7650 3800);
FORCEPROP 1 LAST BODY_TYPE PLUMBING
J 2
(-7650 3850);
DISPLAY 0.872340 (-7650 3850);
PAINT GREEN (-7650 3850);
DISPLAY INVISIBLE (-7650 3850);
FORCEPROP 1 LAST HDL_TAP TRUE
J 2
(-7975 3675);
DISPLAY 0.872340 (-7975 3675);
DISPLAY INVISIBLE (-7975 3675);
FORCEPROP 1 LAST PATH I34
J 2
(-7648 3800);
DISPLAY 0.872340 (-7648 3800);
PAINT GREEN (-7648 3800);
DISPLAY INVISIBLE (-7648 3800);
FORCEADD TAP..1
R 2
(-7650 3850);
FORCEPROP 3 LASTPIN (-7600 3850) SIG_NAME M_H_CPU1_SA_CB<4>
J 0
(-7590 3860);
DISPLAY 0.659574 (-7590 3860);
PAINT MONO (-7590 3860);
DISPLAY INVISIBLE (-7590 3860);
FORCEPROP 1 LASTPIN (-7600 3850) BN 4
J 2
(-7588 3858);
DISPLAY 0.489362 (-7588 3858);
PAINT GREEN (-7588 3858);
FORCEPROP 2 LAST CDS_LIB mstr_standard
J 0
(-7650 3850);
DISPLAY 0.723404 (-7650 3850);
PAINT MONO (-7650 3850);
DISPLAY INVISIBLE (-7650 3850);
FORCEPROP 1 LAST BODY_TYPE PLUMBING
J 2
(-7650 3900);
DISPLAY 0.872340 (-7650 3900);
PAINT GREEN (-7650 3900);
DISPLAY INVISIBLE (-7650 3900);
FORCEPROP 1 LAST HDL_TAP TRUE
J 2
(-7975 3725);
DISPLAY 0.872340 (-7975 3725);
DISPLAY INVISIBLE (-7975 3725);
FORCEPROP 1 LAST PATH I35
J 2
(-7648 3850);
DISPLAY 0.872340 (-7648 3850);
PAINT GREEN (-7648 3850);
DISPLAY INVISIBLE (-7648 3850);
FORCEADD TAP..1
(-5950 2200);
FORCEPROP 3 LASTPIN (-6000 2200) SIG_NAME M_H_CPU1_SB_DQ<0>
J 0
(-5990 2210);
DISPLAY 0.659574 (-5990 2210);
PAINT MONO (-5990 2210);
DISPLAY INVISIBLE (-5990 2210);
FORCEPROP 1 LASTPIN (-6000 2200) BN 0
J 0
(-6012 2208);
DISPLAY 0.489362 (-6012 2208);
PAINT GREEN (-6012 2208);
FORCEPROP 2 LAST CDS_LIB mstr_standard
J 0
(-5950 2200);
DISPLAY 0.723404 (-5950 2200);
PAINT MONO (-5950 2200);
DISPLAY INVISIBLE (-5950 2200);
FORCEPROP 1 LAST BODY_TYPE PLUMBING
J 0
(-5950 2250);
DISPLAY 0.872340 (-5950 2250);
PAINT GREEN (-5950 2250);
DISPLAY INVISIBLE (-5950 2250);
FORCEPROP 1 LAST HDL_TAP TRUE
J 0
(-5625 2075);
DISPLAY 0.872340 (-5625 2075);
DISPLAY INVISIBLE (-5625 2075);
FORCEPROP 1 LAST PATH I36
J 0
(-5952 2200);
DISPLAY 0.872340 (-5952 2200);
PAINT GREEN (-5952 2200);
DISPLAY INVISIBLE (-5952 2200);
FORCEADD TAP..1
(-5950 2300);
FORCEPROP 3 LASTPIN (-6000 2300) SIG_NAME M_H_CPU1_SB_DQ<2>
J 0
(-5990 2310);
DISPLAY 0.659574 (-5990 2310);
PAINT MONO (-5990 2310);
DISPLAY INVISIBLE (-5990 2310);
FORCEPROP 1 LASTPIN (-6000 2300) BN 2
J 0
(-6012 2308);
DISPLAY 0.489362 (-6012 2308);
PAINT GREEN (-6012 2308);
FORCEPROP 2 LAST CDS_LIB mstr_standard
J 0
(-5950 2300);
DISPLAY 0.723404 (-5950 2300);
PAINT MONO (-5950 2300);
DISPLAY INVISIBLE (-5950 2300);
FORCEPROP 1 LAST BODY_TYPE PLUMBING
J 0
(-5950 2350);
DISPLAY 0.872340 (-5950 2350);
PAINT GREEN (-5950 2350);
DISPLAY INVISIBLE (-5950 2350);
FORCEPROP 1 LAST HDL_TAP TRUE
J 0
(-5625 2175);
DISPLAY 0.872340 (-5625 2175);
DISPLAY INVISIBLE (-5625 2175);
FORCEPROP 1 LAST PATH I37
J 0
(-5952 2300);
DISPLAY 0.872340 (-5952 2300);
PAINT GREEN (-5952 2300);
DISPLAY INVISIBLE (-5952 2300);
FORCEADD TAP..1
(-5950 2350);
FORCEPROP 3 LASTPIN (-6000 2350) SIG_NAME M_H_CPU1_SB_DQ<3>
J 0
(-5990 2360);
DISPLAY 0.659574 (-5990 2360);
PAINT MONO (-5990 2360);
DISPLAY INVISIBLE (-5990 2360);
FORCEPROP 1 LASTPIN (-6000 2350) BN 3
J 0
(-6012 2358);
DISPLAY 0.489362 (-6012 2358);
PAINT GREEN (-6012 2358);
FORCEPROP 2 LAST CDS_LIB mstr_standard
J 0
(-5950 2350);
DISPLAY 0.723404 (-5950 2350);
PAINT MONO (-5950 2350);
DISPLAY INVISIBLE (-5950 2350);
FORCEPROP 1 LAST BODY_TYPE PLUMBING
J 0
(-5950 2400);
DISPLAY 0.872340 (-5950 2400);
PAINT GREEN (-5950 2400);
DISPLAY INVISIBLE (-5950 2400);
FORCEPROP 1 LAST HDL_TAP TRUE
J 0
(-5625 2225);
DISPLAY 0.872340 (-5625 2225);
DISPLAY INVISIBLE (-5625 2225);
FORCEPROP 1 LAST PATH I38
J 0
(-5952 2350);
DISPLAY 0.872340 (-5952 2350);
PAINT GREEN (-5952 2350);
DISPLAY INVISIBLE (-5952 2350);
FORCEADD TAP..1
(-5950 2250);
FORCEPROP 3 LASTPIN (-6000 2250) SIG_NAME M_H_CPU1_SB_DQ<1>
J 0
(-5990 2260);
DISPLAY 0.659574 (-5990 2260);
PAINT MONO (-5990 2260);
DISPLAY INVISIBLE (-5990 2260);
FORCEPROP 1 LASTPIN (-6000 2250) BN 1
J 0
(-6012 2258);
DISPLAY 0.489362 (-6012 2258);
PAINT GREEN (-6012 2258);
FORCEPROP 2 LAST CDS_LIB mstr_standard
J 0
(-5950 2250);
DISPLAY 0.723404 (-5950 2250);
PAINT MONO (-5950 2250);
DISPLAY INVISIBLE (-5950 2250);
FORCEPROP 1 LAST BODY_TYPE PLUMBING
J 0
(-5950 2300);
DISPLAY 0.872340 (-5950 2300);
PAINT GREEN (-5950 2300);
DISPLAY INVISIBLE (-5950 2300);
FORCEPROP 1 LAST HDL_TAP TRUE
J 0
(-5625 2125);
DISPLAY 0.872340 (-5625 2125);
DISPLAY INVISIBLE (-5625 2125);
FORCEPROP 1 LAST PATH I39
J 0
(-5952 2250);
DISPLAY 0.872340 (-5952 2250);
PAINT GREEN (-5952 2250);
DISPLAY INVISIBLE (-5952 2250);
FORCEADD TAP..1
(-5950 2400);
FORCEPROP 3 LASTPIN (-6000 2400) SIG_NAME M_H_CPU1_SB_DQ<4>
J 0
(-5990 2410);
DISPLAY 0.659574 (-5990 2410);
PAINT MONO (-5990 2410);
DISPLAY INVISIBLE (-5990 2410);
FORCEPROP 1 LASTPIN (-6000 2400) BN 4
J 0
(-6012 2408);
DISPLAY 0.489362 (-6012 2408);
PAINT GREEN (-6012 2408);
FORCEPROP 2 LAST CDS_LIB mstr_standard
J 0
(-5950 2400);
DISPLAY 0.723404 (-5950 2400);
PAINT MONO (-5950 2400);
DISPLAY INVISIBLE (-5950 2400);
FORCEPROP 1 LAST BODY_TYPE PLUMBING
J 0
(-5950 2450);
DISPLAY 0.872340 (-5950 2450);
PAINT GREEN (-5950 2450);
DISPLAY INVISIBLE (-5950 2450);
FORCEPROP 1 LAST HDL_TAP TRUE
J 0
(-5625 2275);
DISPLAY 0.872340 (-5625 2275);
DISPLAY INVISIBLE (-5625 2275);
FORCEPROP 1 LAST PATH I40
J 0
(-5952 2400);
DISPLAY 0.872340 (-5952 2400);
PAINT GREEN (-5952 2400);
DISPLAY INVISIBLE (-5952 2400);
FORCEADD TAP..1
(-5950 2450);
FORCEPROP 3 LASTPIN (-6000 2450) SIG_NAME M_H_CPU1_SB_DQ<5>
J 0
(-5990 2460);
DISPLAY 0.659574 (-5990 2460);
PAINT MONO (-5990 2460);
DISPLAY INVISIBLE (-5990 2460);
FORCEPROP 1 LASTPIN (-6000 2450) BN 5
J 0
(-6012 2458);
DISPLAY 0.489362 (-6012 2458);
PAINT GREEN (-6012 2458);
FORCEPROP 2 LAST CDS_LIB mstr_standard
J 0
(-5950 2450);
DISPLAY 0.723404 (-5950 2450);
PAINT MONO (-5950 2450);
DISPLAY INVISIBLE (-5950 2450);
FORCEPROP 1 LAST BODY_TYPE PLUMBING
J 0
(-5950 2500);
DISPLAY 0.872340 (-5950 2500);
PAINT GREEN (-5950 2500);
DISPLAY INVISIBLE (-5950 2500);
FORCEPROP 1 LAST HDL_TAP TRUE
J 0
(-5625 2325);
DISPLAY 0.872340 (-5625 2325);
DISPLAY INVISIBLE (-5625 2325);
FORCEPROP 1 LAST PATH I41
J 0
(-5952 2450);
DISPLAY 0.872340 (-5952 2450);
PAINT GREEN (-5952 2450);
DISPLAY INVISIBLE (-5952 2450);
FORCEADD TAP..1
(-5950 2500);
FORCEPROP 3 LASTPIN (-6000 2500) SIG_NAME M_H_CPU1_SB_DQ<6>
J 0
(-5990 2510);
DISPLAY 0.659574 (-5990 2510);
PAINT MONO (-5990 2510);
DISPLAY INVISIBLE (-5990 2510);
FORCEPROP 1 LASTPIN (-6000 2500) BN 6
J 0
(-6012 2508);
DISPLAY 0.489362 (-6012 2508);
PAINT GREEN (-6012 2508);
FORCEPROP 2 LAST CDS_LIB mstr_standard
J 0
(-5950 2500);
DISPLAY 0.723404 (-5950 2500);
PAINT MONO (-5950 2500);
DISPLAY INVISIBLE (-5950 2500);
FORCEPROP 1 LAST BODY_TYPE PLUMBING
J 0
(-5950 2550);
DISPLAY 0.872340 (-5950 2550);
PAINT GREEN (-5950 2550);
DISPLAY INVISIBLE (-5950 2550);
FORCEPROP 1 LAST HDL_TAP TRUE
J 0
(-5625 2375);
DISPLAY 0.872340 (-5625 2375);
DISPLAY INVISIBLE (-5625 2375);
FORCEPROP 1 LAST PATH I42
J 0
(-5952 2500);
DISPLAY 0.872340 (-5952 2500);
PAINT GREEN (-5952 2500);
DISPLAY INVISIBLE (-5952 2500);
FORCEADD TAP..1
(-5950 2550);
FORCEPROP 3 LASTPIN (-6000 2550) SIG_NAME M_H_CPU1_SB_DQ<7>
J 0
(-5990 2560);
DISPLAY 0.659574 (-5990 2560);
PAINT MONO (-5990 2560);
DISPLAY INVISIBLE (-5990 2560);
FORCEPROP 1 LASTPIN (-6000 2550) BN 7
J 0
(-6012 2558);
DISPLAY 0.489362 (-6012 2558);
PAINT GREEN (-6012 2558);
FORCEPROP 2 LAST CDS_LIB mstr_standard
J 0
(-5950 2550);
DISPLAY 0.723404 (-5950 2550);
PAINT MONO (-5950 2550);
DISPLAY INVISIBLE (-5950 2550);
FORCEPROP 1 LAST BODY_TYPE PLUMBING
J 0
(-5950 2600);
DISPLAY 0.872340 (-5950 2600);
PAINT GREEN (-5950 2600);
DISPLAY INVISIBLE (-5950 2600);
FORCEPROP 1 LAST HDL_TAP TRUE
J 0
(-5625 2425);
DISPLAY 0.872340 (-5625 2425);
DISPLAY INVISIBLE (-5625 2425);
FORCEPROP 1 LAST PATH I43
J 0
(-5952 2550);
DISPLAY 0.872340 (-5952 2550);
PAINT GREEN (-5952 2550);
DISPLAY INVISIBLE (-5952 2550);
FORCEADD TAP..1
(-5950 2600);
FORCEPROP 3 LASTPIN (-6000 2600) SIG_NAME M_H_CPU1_SB_DQ<8>
J 0
(-5990 2610);
DISPLAY 0.659574 (-5990 2610);
PAINT MONO (-5990 2610);
DISPLAY INVISIBLE (-5990 2610);
FORCEPROP 1 LASTPIN (-6000 2600) BN 8
J 0
(-6012 2608);
DISPLAY 0.489362 (-6012 2608);
PAINT GREEN (-6012 2608);
FORCEPROP 2 LAST CDS_LIB mstr_standard
J 0
(-5950 2600);
DISPLAY 0.723404 (-5950 2600);
PAINT MONO (-5950 2600);
DISPLAY INVISIBLE (-5950 2600);
FORCEPROP 1 LAST BODY_TYPE PLUMBING
J 0
(-5950 2650);
DISPLAY 0.872340 (-5950 2650);
PAINT GREEN (-5950 2650);
DISPLAY INVISIBLE (-5950 2650);
FORCEPROP 1 LAST HDL_TAP TRUE
J 0
(-5625 2475);
DISPLAY 0.872340 (-5625 2475);
DISPLAY INVISIBLE (-5625 2475);
FORCEPROP 1 LAST PATH I44
J 0
(-5952 2600);
DISPLAY 0.872340 (-5952 2600);
PAINT GREEN (-5952 2600);
DISPLAY INVISIBLE (-5952 2600);
FORCEADD TAP..1
(-5950 2650);
FORCEPROP 3 LASTPIN (-6000 2650) SIG_NAME M_H_CPU1_SB_DQ<9>
J 0
(-5990 2660);
DISPLAY 0.659574 (-5990 2660);
PAINT MONO (-5990 2660);
DISPLAY INVISIBLE (-5990 2660);
FORCEPROP 1 LASTPIN (-6000 2650) BN 9
J 0
(-6012 2658);
DISPLAY 0.489362 (-6012 2658);
PAINT GREEN (-6012 2658);
FORCEPROP 2 LAST CDS_LIB mstr_standard
J 0
(-5950 2650);
DISPLAY 0.723404 (-5950 2650);
PAINT MONO (-5950 2650);
DISPLAY INVISIBLE (-5950 2650);
FORCEPROP 1 LAST BODY_TYPE PLUMBING
J 0
(-5950 2700);
DISPLAY 0.872340 (-5950 2700);
PAINT GREEN (-5950 2700);
DISPLAY INVISIBLE (-5950 2700);
FORCEPROP 1 LAST HDL_TAP TRUE
J 0
(-5625 2525);
DISPLAY 0.872340 (-5625 2525);
DISPLAY INVISIBLE (-5625 2525);
FORCEPROP 1 LAST PATH I45
J 0
(-5952 2650);
DISPLAY 0.872340 (-5952 2650);
PAINT GREEN (-5952 2650);
DISPLAY INVISIBLE (-5952 2650);
FORCEADD TAP..1
(-5950 2700);
FORCEPROP 3 LASTPIN (-6000 2700) SIG_NAME M_H_CPU1_SB_DQ<10>
J 0
(-5990 2710);
DISPLAY 0.659574 (-5990 2710);
PAINT MONO (-5990 2710);
DISPLAY INVISIBLE (-5990 2710);
FORCEPROP 1 LASTPIN (-6000 2700) BN 10
J 0
(-6012 2708);
DISPLAY 0.489362 (-6012 2708);
PAINT GREEN (-6012 2708);
FORCEPROP 2 LAST CDS_LIB mstr_standard
J 0
(-5950 2700);
DISPLAY 0.723404 (-5950 2700);
PAINT MONO (-5950 2700);
DISPLAY INVISIBLE (-5950 2700);
FORCEPROP 1 LAST BODY_TYPE PLUMBING
J 0
(-5950 2750);
DISPLAY 0.872340 (-5950 2750);
PAINT GREEN (-5950 2750);
DISPLAY INVISIBLE (-5950 2750);
FORCEPROP 1 LAST HDL_TAP TRUE
J 0
(-5625 2575);
DISPLAY 0.872340 (-5625 2575);
DISPLAY INVISIBLE (-5625 2575);
FORCEPROP 1 LAST PATH I46
J 0
(-5952 2700);
DISPLAY 0.872340 (-5952 2700);
PAINT GREEN (-5952 2700);
DISPLAY INVISIBLE (-5952 2700);
FORCEADD TAP..1
(-5950 2750);
FORCEPROP 3 LASTPIN (-6000 2750) SIG_NAME M_H_CPU1_SB_DQ<11>
J 0
(-5990 2760);
DISPLAY 0.659574 (-5990 2760);
PAINT MONO (-5990 2760);
DISPLAY INVISIBLE (-5990 2760);
FORCEPROP 1 LASTPIN (-6000 2750) BN 11
J 0
(-6012 2758);
DISPLAY 0.489362 (-6012 2758);
PAINT GREEN (-6012 2758);
FORCEPROP 2 LAST CDS_LIB mstr_standard
J 0
(-5950 2750);
DISPLAY 0.723404 (-5950 2750);
PAINT MONO (-5950 2750);
DISPLAY INVISIBLE (-5950 2750);
FORCEPROP 1 LAST BODY_TYPE PLUMBING
J 0
(-5950 2800);
DISPLAY 0.872340 (-5950 2800);
PAINT GREEN (-5950 2800);
DISPLAY INVISIBLE (-5950 2800);
FORCEPROP 1 LAST HDL_TAP TRUE
J 0
(-5625 2625);
DISPLAY 0.872340 (-5625 2625);
DISPLAY INVISIBLE (-5625 2625);
FORCEPROP 1 LAST PATH I47
J 0
(-5952 2750);
DISPLAY 0.872340 (-5952 2750);
PAINT GREEN (-5952 2750);
DISPLAY INVISIBLE (-5952 2750);
FORCEADD TAP..1
(-5950 2850);
FORCEPROP 3 LASTPIN (-6000 2850) SIG_NAME M_H_CPU1_SB_DQ<13>
J 0
(-5990 2860);
DISPLAY 0.659574 (-5990 2860);
PAINT MONO (-5990 2860);
DISPLAY INVISIBLE (-5990 2860);
FORCEPROP 1 LASTPIN (-6000 2850) BN 13
J 0
(-6012 2858);
DISPLAY 0.489362 (-6012 2858);
PAINT GREEN (-6012 2858);
FORCEPROP 2 LAST CDS_LIB mstr_standard
J 0
(-5950 2850);
DISPLAY 0.723404 (-5950 2850);
PAINT MONO (-5950 2850);
DISPLAY INVISIBLE (-5950 2850);
FORCEPROP 1 LAST BODY_TYPE PLUMBING
J 0
(-5950 2900);
DISPLAY 0.872340 (-5950 2900);
PAINT GREEN (-5950 2900);
DISPLAY INVISIBLE (-5950 2900);
FORCEPROP 1 LAST HDL_TAP TRUE
J 0
(-5625 2725);
DISPLAY 0.872340 (-5625 2725);
DISPLAY INVISIBLE (-5625 2725);
FORCEPROP 1 LAST PATH I48
J 0
(-5952 2850);
DISPLAY 0.872340 (-5952 2850);
PAINT GREEN (-5952 2850);
DISPLAY INVISIBLE (-5952 2850);
FORCEADD TAP..1
(-5950 2800);
FORCEPROP 3 LASTPIN (-6000 2800) SIG_NAME M_H_CPU1_SB_DQ<12>
J 0
(-5990 2810);
DISPLAY 0.659574 (-5990 2810);
PAINT MONO (-5990 2810);
DISPLAY INVISIBLE (-5990 2810);
FORCEPROP 1 LASTPIN (-6000 2800) BN 12
J 0
(-6012 2808);
DISPLAY 0.489362 (-6012 2808);
PAINT GREEN (-6012 2808);
FORCEPROP 2 LAST CDS_LIB mstr_standard
J 0
(-5950 2800);
DISPLAY 0.723404 (-5950 2800);
PAINT MONO (-5950 2800);
DISPLAY INVISIBLE (-5950 2800);
FORCEPROP 1 LAST BODY_TYPE PLUMBING
J 0
(-5950 2850);
DISPLAY 0.872340 (-5950 2850);
PAINT GREEN (-5950 2850);
DISPLAY INVISIBLE (-5950 2850);
FORCEPROP 1 LAST HDL_TAP TRUE
J 0
(-5625 2675);
DISPLAY 0.872340 (-5625 2675);
DISPLAY INVISIBLE (-5625 2675);
FORCEPROP 1 LAST PATH I49
J 0
(-5952 2800);
DISPLAY 0.872340 (-5952 2800);
PAINT GREEN (-5952 2800);
DISPLAY INVISIBLE (-5952 2800);
FORCEADD TAP..1
(-5950 2900);
FORCEPROP 3 LASTPIN (-6000 2900) SIG_NAME M_H_CPU1_SB_DQ<14>
J 0
(-5990 2910);
DISPLAY 0.659574 (-5990 2910);
PAINT MONO (-5990 2910);
DISPLAY INVISIBLE (-5990 2910);
FORCEPROP 1 LASTPIN (-6000 2900) BN 14
J 0
(-6012 2908);
DISPLAY 0.489362 (-6012 2908);
PAINT GREEN (-6012 2908);
FORCEPROP 2 LAST CDS_LIB mstr_standard
J 0
(-5950 2900);
DISPLAY 0.723404 (-5950 2900);
PAINT MONO (-5950 2900);
DISPLAY INVISIBLE (-5950 2900);
FORCEPROP 1 LAST BODY_TYPE PLUMBING
J 0
(-5950 2950);
DISPLAY 0.872340 (-5950 2950);
PAINT GREEN (-5950 2950);
DISPLAY INVISIBLE (-5950 2950);
FORCEPROP 1 LAST HDL_TAP TRUE
J 0
(-5625 2775);
DISPLAY 0.872340 (-5625 2775);
DISPLAY INVISIBLE (-5625 2775);
FORCEPROP 1 LAST PATH I50
J 0
(-5952 2900);
DISPLAY 0.872340 (-5952 2900);
PAINT GREEN (-5952 2900);
DISPLAY INVISIBLE (-5952 2900);
FORCEADD TAP..1
(-5950 2950);
FORCEPROP 3 LASTPIN (-6000 2950) SIG_NAME M_H_CPU1_SB_DQ<15>
J 0
(-5990 2960);
DISPLAY 0.659574 (-5990 2960);
PAINT MONO (-5990 2960);
DISPLAY INVISIBLE (-5990 2960);
FORCEPROP 1 LASTPIN (-6000 2950) BN 15
J 0
(-6012 2958);
DISPLAY 0.489362 (-6012 2958);
PAINT GREEN (-6012 2958);
FORCEPROP 2 LAST CDS_LIB mstr_standard
J 0
(-5950 2950);
DISPLAY 0.723404 (-5950 2950);
PAINT MONO (-5950 2950);
DISPLAY INVISIBLE (-5950 2950);
FORCEPROP 1 LAST BODY_TYPE PLUMBING
J 0
(-5950 3000);
DISPLAY 0.872340 (-5950 3000);
PAINT GREEN (-5950 3000);
DISPLAY INVISIBLE (-5950 3000);
FORCEPROP 1 LAST HDL_TAP TRUE
J 0
(-5625 2825);
DISPLAY 0.872340 (-5625 2825);
DISPLAY INVISIBLE (-5625 2825);
FORCEPROP 1 LAST PATH I51
J 0
(-5952 2950);
DISPLAY 0.872340 (-5952 2950);
PAINT GREEN (-5952 2950);
DISPLAY INVISIBLE (-5952 2950);
FORCEADD TAP..1
(-5950 3000);
FORCEPROP 3 LASTPIN (-6000 3000) SIG_NAME M_H_CPU1_SB_DQ<16>
J 0
(-5990 3010);
DISPLAY 0.659574 (-5990 3010);
PAINT MONO (-5990 3010);
DISPLAY INVISIBLE (-5990 3010);
FORCEPROP 1 LASTPIN (-6000 3000) BN 16
J 0
(-6012 3008);
DISPLAY 0.489362 (-6012 3008);
PAINT GREEN (-6012 3008);
FORCEPROP 2 LAST CDS_LIB mstr_standard
J 0
(-5950 3000);
DISPLAY 0.723404 (-5950 3000);
PAINT MONO (-5950 3000);
DISPLAY INVISIBLE (-5950 3000);
FORCEPROP 1 LAST BODY_TYPE PLUMBING
J 0
(-5950 3050);
DISPLAY 0.872340 (-5950 3050);
PAINT GREEN (-5950 3050);
DISPLAY INVISIBLE (-5950 3050);
FORCEPROP 1 LAST HDL_TAP TRUE
J 0
(-5625 2875);
DISPLAY 0.872340 (-5625 2875);
DISPLAY INVISIBLE (-5625 2875);
FORCEPROP 1 LAST PATH I52
J 0
(-5952 3000);
DISPLAY 0.872340 (-5952 3000);
PAINT GREEN (-5952 3000);
DISPLAY INVISIBLE (-5952 3000);
FORCEADD TAP..1
(-5950 3050);
FORCEPROP 3 LASTPIN (-6000 3050) SIG_NAME M_H_CPU1_SB_DQ<17>
J 0
(-5990 3060);
DISPLAY 0.659574 (-5990 3060);
PAINT MONO (-5990 3060);
DISPLAY INVISIBLE (-5990 3060);
FORCEPROP 1 LASTPIN (-6000 3050) BN 17
J 0
(-6012 3058);
DISPLAY 0.489362 (-6012 3058);
PAINT GREEN (-6012 3058);
FORCEPROP 2 LAST CDS_LIB mstr_standard
J 0
(-5950 3050);
DISPLAY 0.723404 (-5950 3050);
PAINT MONO (-5950 3050);
DISPLAY INVISIBLE (-5950 3050);
FORCEPROP 1 LAST BODY_TYPE PLUMBING
J 0
(-5950 3100);
DISPLAY 0.872340 (-5950 3100);
PAINT GREEN (-5950 3100);
DISPLAY INVISIBLE (-5950 3100);
FORCEPROP 1 LAST HDL_TAP TRUE
J 0
(-5625 2925);
DISPLAY 0.872340 (-5625 2925);
DISPLAY INVISIBLE (-5625 2925);
FORCEPROP 1 LAST PATH I53
J 0
(-5952 3050);
DISPLAY 0.872340 (-5952 3050);
PAINT GREEN (-5952 3050);
DISPLAY INVISIBLE (-5952 3050);
FORCEADD TAP..1
(-5950 3100);
FORCEPROP 3 LASTPIN (-6000 3100) SIG_NAME M_H_CPU1_SB_DQ<18>
J 0
(-5990 3110);
DISPLAY 0.659574 (-5990 3110);
PAINT MONO (-5990 3110);
DISPLAY INVISIBLE (-5990 3110);
FORCEPROP 1 LASTPIN (-6000 3100) BN 18
J 0
(-6012 3108);
DISPLAY 0.489362 (-6012 3108);
PAINT GREEN (-6012 3108);
FORCEPROP 2 LAST CDS_LIB mstr_standard
J 0
(-5950 3100);
DISPLAY 0.723404 (-5950 3100);
PAINT MONO (-5950 3100);
DISPLAY INVISIBLE (-5950 3100);
FORCEPROP 1 LAST BODY_TYPE PLUMBING
J 0
(-5950 3150);
DISPLAY 0.872340 (-5950 3150);
PAINT GREEN (-5950 3150);
DISPLAY INVISIBLE (-5950 3150);
FORCEPROP 1 LAST HDL_TAP TRUE
J 0
(-5625 2975);
DISPLAY 0.872340 (-5625 2975);
DISPLAY INVISIBLE (-5625 2975);
FORCEPROP 1 LAST PATH I54
J 0
(-5952 3100);
DISPLAY 0.872340 (-5952 3100);
PAINT GREEN (-5952 3100);
DISPLAY INVISIBLE (-5952 3100);
FORCEADD TAP..1
(-5950 3150);
FORCEPROP 3 LASTPIN (-6000 3150) SIG_NAME M_H_CPU1_SB_DQ<19>
J 0
(-5990 3160);
DISPLAY 0.659574 (-5990 3160);
PAINT MONO (-5990 3160);
DISPLAY INVISIBLE (-5990 3160);
FORCEPROP 1 LASTPIN (-6000 3150) BN 19
J 0
(-6012 3158);
DISPLAY 0.489362 (-6012 3158);
PAINT GREEN (-6012 3158);
FORCEPROP 2 LAST CDS_LIB mstr_standard
J 0
(-5950 3150);
DISPLAY 0.723404 (-5950 3150);
PAINT MONO (-5950 3150);
DISPLAY INVISIBLE (-5950 3150);
FORCEPROP 1 LAST BODY_TYPE PLUMBING
J 0
(-5950 3200);
DISPLAY 0.872340 (-5950 3200);
PAINT GREEN (-5950 3200);
DISPLAY INVISIBLE (-5950 3200);
FORCEPROP 1 LAST HDL_TAP TRUE
J 0
(-5625 3025);
DISPLAY 0.872340 (-5625 3025);
DISPLAY INVISIBLE (-5625 3025);
FORCEPROP 1 LAST PATH I55
J 0
(-5952 3150);
DISPLAY 0.872340 (-5952 3150);
PAINT GREEN (-5952 3150);
DISPLAY INVISIBLE (-5952 3150);
FORCEADD TAP..1
(-5950 3200);
FORCEPROP 3 LASTPIN (-6000 3200) SIG_NAME M_H_CPU1_SB_DQ<20>
J 0
(-5990 3210);
DISPLAY 0.659574 (-5990 3210);
PAINT MONO (-5990 3210);
DISPLAY INVISIBLE (-5990 3210);
FORCEPROP 1 LASTPIN (-6000 3200) BN 20
J 0
(-6012 3208);
DISPLAY 0.489362 (-6012 3208);
PAINT GREEN (-6012 3208);
FORCEPROP 2 LAST CDS_LIB mstr_standard
J 0
(-5950 3200);
DISPLAY 0.723404 (-5950 3200);
PAINT MONO (-5950 3200);
DISPLAY INVISIBLE (-5950 3200);
FORCEPROP 1 LAST BODY_TYPE PLUMBING
J 0
(-5950 3250);
DISPLAY 0.872340 (-5950 3250);
PAINT GREEN (-5950 3250);
DISPLAY INVISIBLE (-5950 3250);
FORCEPROP 1 LAST HDL_TAP TRUE
J 0
(-5625 3075);
DISPLAY 0.872340 (-5625 3075);
DISPLAY INVISIBLE (-5625 3075);
FORCEPROP 1 LAST PATH I56
J 0
(-5952 3200);
DISPLAY 0.872340 (-5952 3200);
PAINT GREEN (-5952 3200);
DISPLAY INVISIBLE (-5952 3200);
FORCEADD TAP..1
(-5950 3250);
FORCEPROP 3 LASTPIN (-6000 3250) SIG_NAME M_H_CPU1_SB_DQ<21>
J 0
(-5990 3260);
DISPLAY 0.659574 (-5990 3260);
PAINT MONO (-5990 3260);
DISPLAY INVISIBLE (-5990 3260);
FORCEPROP 1 LASTPIN (-6000 3250) BN 21
J 0
(-6012 3258);
DISPLAY 0.489362 (-6012 3258);
PAINT GREEN (-6012 3258);
FORCEPROP 2 LAST CDS_LIB mstr_standard
J 0
(-5950 3250);
DISPLAY 0.723404 (-5950 3250);
PAINT MONO (-5950 3250);
DISPLAY INVISIBLE (-5950 3250);
FORCEPROP 1 LAST BODY_TYPE PLUMBING
J 0
(-5950 3300);
DISPLAY 0.872340 (-5950 3300);
PAINT GREEN (-5950 3300);
DISPLAY INVISIBLE (-5950 3300);
FORCEPROP 1 LAST HDL_TAP TRUE
J 0
(-5625 3125);
DISPLAY 0.872340 (-5625 3125);
DISPLAY INVISIBLE (-5625 3125);
FORCEPROP 1 LAST PATH I57
J 0
(-5952 3250);
DISPLAY 0.872340 (-5952 3250);
PAINT GREEN (-5952 3250);
DISPLAY INVISIBLE (-5952 3250);
FORCEADD TAP..1
(-5950 3300);
FORCEPROP 3 LASTPIN (-6000 3300) SIG_NAME M_H_CPU1_SB_DQ<22>
J 0
(-5990 3310);
DISPLAY 0.659574 (-5990 3310);
PAINT MONO (-5990 3310);
DISPLAY INVISIBLE (-5990 3310);
FORCEPROP 1 LASTPIN (-6000 3300) BN 22
J 0
(-6012 3308);
DISPLAY 0.489362 (-6012 3308);
PAINT GREEN (-6012 3308);
FORCEPROP 2 LAST CDS_LIB mstr_standard
J 0
(-5950 3300);
DISPLAY 0.723404 (-5950 3300);
PAINT MONO (-5950 3300);
DISPLAY INVISIBLE (-5950 3300);
FORCEPROP 1 LAST BODY_TYPE PLUMBING
J 0
(-5950 3350);
DISPLAY 0.872340 (-5950 3350);
PAINT GREEN (-5950 3350);
DISPLAY INVISIBLE (-5950 3350);
FORCEPROP 1 LAST HDL_TAP TRUE
J 0
(-5625 3175);
DISPLAY 0.872340 (-5625 3175);
DISPLAY INVISIBLE (-5625 3175);
FORCEPROP 1 LAST PATH I58
J 0
(-5952 3300);
DISPLAY 0.872340 (-5952 3300);
PAINT GREEN (-5952 3300);
DISPLAY INVISIBLE (-5952 3300);
FORCEADD TAP..1
(-5950 3350);
FORCEPROP 3 LASTPIN (-6000 3350) SIG_NAME M_H_CPU1_SB_DQ<23>
J 0
(-5990 3360);
DISPLAY 0.659574 (-5990 3360);
PAINT MONO (-5990 3360);
DISPLAY INVISIBLE (-5990 3360);
FORCEPROP 1 LASTPIN (-6000 3350) BN 23
J 0
(-6012 3358);
DISPLAY 0.489362 (-6012 3358);
PAINT GREEN (-6012 3358);
FORCEPROP 2 LAST CDS_LIB mstr_standard
J 0
(-5950 3350);
DISPLAY 0.723404 (-5950 3350);
PAINT MONO (-5950 3350);
DISPLAY INVISIBLE (-5950 3350);
FORCEPROP 1 LAST BODY_TYPE PLUMBING
J 0
(-5950 3400);
DISPLAY 0.872340 (-5950 3400);
PAINT GREEN (-5950 3400);
DISPLAY INVISIBLE (-5950 3400);
FORCEPROP 1 LAST HDL_TAP TRUE
J 0
(-5625 3225);
DISPLAY 0.872340 (-5625 3225);
DISPLAY INVISIBLE (-5625 3225);
FORCEPROP 1 LAST PATH I59
J 0
(-5952 3350);
DISPLAY 0.872340 (-5952 3350);
PAINT GREEN (-5952 3350);
DISPLAY INVISIBLE (-5952 3350);
FORCEADD OFFPAGE..1
(-8250 2900);
FORCEPROP 2 LAST $XR0 104 
J 0
(-8532 2900);
DISPLAY 0.638298 (-8532 2900);
PAINT MONO (-8532 2900);
FORCEPROP 2 LAST PATH I6
J 0
(-8650 2950);
DISPLAY 1.021277 (-8650 2950);
DISPLAY INVISIBLE (-8650 2950);
FORCEPROP 1 LAST COMMENT_BODY TRUE
J 0
(-8125 2800);
DISPLAY 0.872340 (-8125 2800);
PAINT GREEN (-8125 2800);
DISPLAY INVISIBLE (-8125 2800);
FORCEPROP 1 LAST OFFPAGE TRUE
J 0
(-7925 2775);
DISPLAY 0.872340 (-7925 2775);
PAINT GREEN (-7925 2775);
DISPLAY INVISIBLE (-7925 2775);
FORCEPROP 2 LAST CDS_LIB mstr_standard
J 0
(-8250 2900);
DISPLAY 0.808511 (-8250 2900);
DISPLAY INVISIBLE (-8250 2900);
FORCEADD TAP..1
(-5950 3400);
FORCEPROP 3 LASTPIN (-6000 3400) SIG_NAME M_H_CPU1_SB_DQ<24>
J 0
(-5990 3410);
DISPLAY 0.659574 (-5990 3410);
PAINT MONO (-5990 3410);
DISPLAY INVISIBLE (-5990 3410);
FORCEPROP 1 LASTPIN (-6000 3400) BN 24
J 0
(-6012 3408);
DISPLAY 0.489362 (-6012 3408);
PAINT GREEN (-6012 3408);
FORCEPROP 2 LAST CDS_LIB mstr_standard
J 0
(-5950 3400);
DISPLAY 0.723404 (-5950 3400);
PAINT MONO (-5950 3400);
DISPLAY INVISIBLE (-5950 3400);
FORCEPROP 1 LAST BODY_TYPE PLUMBING
J 0
(-5950 3450);
DISPLAY 0.872340 (-5950 3450);
PAINT GREEN (-5950 3450);
DISPLAY INVISIBLE (-5950 3450);
FORCEPROP 1 LAST HDL_TAP TRUE
J 0
(-5625 3275);
DISPLAY 0.872340 (-5625 3275);
DISPLAY INVISIBLE (-5625 3275);
FORCEPROP 1 LAST PATH I60
J 0
(-5952 3400);
DISPLAY 0.872340 (-5952 3400);
PAINT GREEN (-5952 3400);
DISPLAY INVISIBLE (-5952 3400);
FORCEADD TAP..1
(-5950 3450);
FORCEPROP 3 LASTPIN (-6000 3450) SIG_NAME M_H_CPU1_SB_DQ<25>
J 0
(-5990 3460);
DISPLAY 0.659574 (-5990 3460);
PAINT MONO (-5990 3460);
DISPLAY INVISIBLE (-5990 3460);
FORCEPROP 1 LASTPIN (-6000 3450) BN 25
J 0
(-6012 3458);
DISPLAY 0.489362 (-6012 3458);
PAINT GREEN (-6012 3458);
FORCEPROP 2 LAST CDS_LIB mstr_standard
J 0
(-5950 3450);
DISPLAY 0.723404 (-5950 3450);
PAINT MONO (-5950 3450);
DISPLAY INVISIBLE (-5950 3450);
FORCEPROP 1 LAST BODY_TYPE PLUMBING
J 0
(-5950 3500);
DISPLAY 0.872340 (-5950 3500);
PAINT GREEN (-5950 3500);
DISPLAY INVISIBLE (-5950 3500);
FORCEPROP 1 LAST HDL_TAP TRUE
J 0
(-5625 3325);
DISPLAY 0.872340 (-5625 3325);
DISPLAY INVISIBLE (-5625 3325);
FORCEPROP 1 LAST PATH I61
J 0
(-5952 3450);
DISPLAY 0.872340 (-5952 3450);
PAINT GREEN (-5952 3450);
DISPLAY INVISIBLE (-5952 3450);
FORCEADD TAP..1
(-5950 3500);
FORCEPROP 3 LASTPIN (-6000 3500) SIG_NAME M_H_CPU1_SB_DQ<26>
J 0
(-5990 3510);
DISPLAY 0.659574 (-5990 3510);
PAINT MONO (-5990 3510);
DISPLAY INVISIBLE (-5990 3510);
FORCEPROP 1 LASTPIN (-6000 3500) BN 26
J 0
(-6012 3508);
DISPLAY 0.489362 (-6012 3508);
PAINT GREEN (-6012 3508);
FORCEPROP 2 LAST CDS_LIB mstr_standard
J 0
(-5950 3500);
DISPLAY 0.723404 (-5950 3500);
PAINT MONO (-5950 3500);
DISPLAY INVISIBLE (-5950 3500);
FORCEPROP 1 LAST BODY_TYPE PLUMBING
J 0
(-5950 3550);
DISPLAY 0.872340 (-5950 3550);
PAINT GREEN (-5950 3550);
DISPLAY INVISIBLE (-5950 3550);
FORCEPROP 1 LAST HDL_TAP TRUE
J 0
(-5625 3375);
DISPLAY 0.872340 (-5625 3375);
DISPLAY INVISIBLE (-5625 3375);
FORCEPROP 1 LAST PATH I62
J 0
(-5952 3500);
DISPLAY 0.872340 (-5952 3500);
PAINT GREEN (-5952 3500);
DISPLAY INVISIBLE (-5952 3500);
FORCEADD TAP..1
(-5950 3550);
FORCEPROP 3 LASTPIN (-6000 3550) SIG_NAME M_H_CPU1_SB_DQ<27>
J 0
(-5990 3560);
DISPLAY 0.659574 (-5990 3560);
PAINT MONO (-5990 3560);
DISPLAY INVISIBLE (-5990 3560);
FORCEPROP 1 LASTPIN (-6000 3550) BN 27
J 0
(-6012 3558);
DISPLAY 0.489362 (-6012 3558);
PAINT GREEN (-6012 3558);
FORCEPROP 2 LAST CDS_LIB mstr_standard
J 0
(-5950 3550);
DISPLAY 0.723404 (-5950 3550);
PAINT MONO (-5950 3550);
DISPLAY INVISIBLE (-5950 3550);
FORCEPROP 1 LAST BODY_TYPE PLUMBING
J 0
(-5950 3600);
DISPLAY 0.872340 (-5950 3600);
PAINT GREEN (-5950 3600);
DISPLAY INVISIBLE (-5950 3600);
FORCEPROP 1 LAST HDL_TAP TRUE
J 0
(-5625 3425);
DISPLAY 0.872340 (-5625 3425);
DISPLAY INVISIBLE (-5625 3425);
FORCEPROP 1 LAST PATH I63
J 0
(-5952 3550);
DISPLAY 0.872340 (-5952 3550);
PAINT GREEN (-5952 3550);
DISPLAY INVISIBLE (-5952 3550);
FORCEADD TAP..1
(-5950 3600);
FORCEPROP 3 LASTPIN (-6000 3600) SIG_NAME M_H_CPU1_SB_DQ<28>
J 0
(-5990 3610);
DISPLAY 0.659574 (-5990 3610);
PAINT MONO (-5990 3610);
DISPLAY INVISIBLE (-5990 3610);
FORCEPROP 1 LASTPIN (-6000 3600) BN 28
J 0
(-6012 3608);
DISPLAY 0.489362 (-6012 3608);
PAINT GREEN (-6012 3608);
FORCEPROP 2 LAST CDS_LIB mstr_standard
J 0
(-5950 3600);
DISPLAY 0.723404 (-5950 3600);
PAINT MONO (-5950 3600);
DISPLAY INVISIBLE (-5950 3600);
FORCEPROP 1 LAST BODY_TYPE PLUMBING
J 0
(-5950 3650);
DISPLAY 0.872340 (-5950 3650);
PAINT GREEN (-5950 3650);
DISPLAY INVISIBLE (-5950 3650);
FORCEPROP 1 LAST HDL_TAP TRUE
J 0
(-5625 3475);
DISPLAY 0.872340 (-5625 3475);
DISPLAY INVISIBLE (-5625 3475);
FORCEPROP 1 LAST PATH I64
J 0
(-5952 3600);
DISPLAY 0.872340 (-5952 3600);
PAINT GREEN (-5952 3600);
DISPLAY INVISIBLE (-5952 3600);
FORCEADD TAP..1
(-5950 3650);
FORCEPROP 3 LASTPIN (-6000 3650) SIG_NAME M_H_CPU1_SB_DQ<29>
J 0
(-5990 3660);
DISPLAY 0.659574 (-5990 3660);
PAINT MONO (-5990 3660);
DISPLAY INVISIBLE (-5990 3660);
FORCEPROP 1 LASTPIN (-6000 3650) BN 29
J 0
(-6012 3658);
DISPLAY 0.489362 (-6012 3658);
PAINT GREEN (-6012 3658);
FORCEPROP 2 LAST CDS_LIB mstr_standard
J 0
(-5950 3650);
DISPLAY 0.723404 (-5950 3650);
PAINT MONO (-5950 3650);
DISPLAY INVISIBLE (-5950 3650);
FORCEPROP 1 LAST BODY_TYPE PLUMBING
J 0
(-5950 3700);
DISPLAY 0.872340 (-5950 3700);
PAINT GREEN (-5950 3700);
DISPLAY INVISIBLE (-5950 3700);
FORCEPROP 1 LAST HDL_TAP TRUE
J 0
(-5625 3525);
DISPLAY 0.872340 (-5625 3525);
DISPLAY INVISIBLE (-5625 3525);
FORCEPROP 1 LAST PATH I65
J 0
(-5952 3650);
DISPLAY 0.872340 (-5952 3650);
PAINT GREEN (-5952 3650);
DISPLAY INVISIBLE (-5952 3650);
FORCEADD TAP..1
(-5950 3750);
FORCEPROP 3 LASTPIN (-6000 3750) SIG_NAME M_H_CPU1_SB_DQ<31>
J 0
(-5990 3760);
DISPLAY 0.659574 (-5990 3760);
PAINT MONO (-5990 3760);
DISPLAY INVISIBLE (-5990 3760);
FORCEPROP 1 LASTPIN (-6000 3750) BN 31
J 0
(-6012 3758);
DISPLAY 0.489362 (-6012 3758);
PAINT GREEN (-6012 3758);
FORCEPROP 2 LAST CDS_LIB mstr_standard
J 0
(-5950 3750);
DISPLAY 0.723404 (-5950 3750);
PAINT MONO (-5950 3750);
DISPLAY INVISIBLE (-5950 3750);
FORCEPROP 1 LAST BODY_TYPE PLUMBING
J 0
(-5950 3800);
DISPLAY 0.872340 (-5950 3800);
PAINT GREEN (-5950 3800);
DISPLAY INVISIBLE (-5950 3800);
FORCEPROP 1 LAST HDL_TAP TRUE
J 0
(-5625 3625);
DISPLAY 0.872340 (-5625 3625);
DISPLAY INVISIBLE (-5625 3625);
FORCEPROP 1 LAST PATH I66
J 0
(-5952 3750);
DISPLAY 0.872340 (-5952 3750);
PAINT GREEN (-5952 3750);
DISPLAY INVISIBLE (-5952 3750);
FORCEADD TAP..1
(-5950 3700);
FORCEPROP 3 LASTPIN (-6000 3700) SIG_NAME M_H_CPU1_SB_DQ<30>
J 0
(-5990 3710);
DISPLAY 0.659574 (-5990 3710);
PAINT MONO (-5990 3710);
DISPLAY INVISIBLE (-5990 3710);
FORCEPROP 1 LASTPIN (-6000 3700) BN 30
J 0
(-6012 3708);
DISPLAY 0.489362 (-6012 3708);
PAINT GREEN (-6012 3708);
FORCEPROP 2 LAST CDS_LIB mstr_standard
J 0
(-5950 3700);
DISPLAY 0.723404 (-5950 3700);
PAINT MONO (-5950 3700);
DISPLAY INVISIBLE (-5950 3700);
FORCEPROP 1 LAST BODY_TYPE PLUMBING
J 0
(-5950 3750);
DISPLAY 0.872340 (-5950 3750);
PAINT GREEN (-5950 3750);
DISPLAY INVISIBLE (-5950 3750);
FORCEPROP 1 LAST HDL_TAP TRUE
J 0
(-5625 3575);
DISPLAY 0.872340 (-5625 3575);
DISPLAY INVISIBLE (-5625 3575);
FORCEPROP 1 LAST PATH I67
J 0
(-5952 3700);
DISPLAY 0.872340 (-5952 3700);
PAINT GREEN (-5952 3700);
DISPLAY INVISIBLE (-5952 3700);
FORCEADD TAP..1
(-5950 3850);
FORCEPROP 3 LASTPIN (-6000 3850) SIG_NAME M_H_CPU1_SA_DQ<0>
J 0
(-5990 3860);
DISPLAY 0.659574 (-5990 3860);
PAINT MONO (-5990 3860);
DISPLAY INVISIBLE (-5990 3860);
FORCEPROP 1 LASTPIN (-6000 3850) BN 0
J 0
(-6012 3858);
DISPLAY 0.489362 (-6012 3858);
PAINT GREEN (-6012 3858);
FORCEPROP 2 LAST CDS_LIB mstr_standard
J 0
(-5950 3850);
DISPLAY 0.723404 (-5950 3850);
PAINT MONO (-5950 3850);
DISPLAY INVISIBLE (-5950 3850);
FORCEPROP 1 LAST BODY_TYPE PLUMBING
J 0
(-5950 3900);
DISPLAY 0.872340 (-5950 3900);
PAINT GREEN (-5950 3900);
DISPLAY INVISIBLE (-5950 3900);
FORCEPROP 1 LAST HDL_TAP TRUE
J 0
(-5625 3725);
DISPLAY 0.872340 (-5625 3725);
DISPLAY INVISIBLE (-5625 3725);
FORCEPROP 1 LAST PATH I68
J 0
(-5952 3850);
DISPLAY 0.872340 (-5952 3850);
PAINT GREEN (-5952 3850);
DISPLAY INVISIBLE (-5952 3850);
FORCEADD OFFPAGE..5
(-8100 3050);
FORCEPROP 2 LAST $XR0 44 
J 0
(-8324 3050);
DISPLAY 0.638298 (-8324 3050);
PAINT MONO (-8324 3050);
FORCEPROP 2 LAST PATH I7
J 0
(-8300 3100);
DISPLAY 1.021277 (-8300 3100);
DISPLAY INVISIBLE (-8300 3100);
FORCEPROP 1 LAST COMMENT_BODY TRUE
J 0
(-8000 2975);
DISPLAY 0.872340 (-8000 2975);
PAINT GREEN (-8000 2975);
DISPLAY INVISIBLE (-8000 2975);
FORCEPROP 1 LAST OFFPAGE TRUE
J 0
(-7775 2925);
DISPLAY 0.872340 (-7775 2925);
PAINT GREEN (-7775 2925);
DISPLAY INVISIBLE (-7775 2925);
FORCEPROP 2 LAST CDS_LIB mstr_standard
J 0
(-8100 3050);
DISPLAY INVISIBLE (-8100 3050);
FORCEADD OFFPAGE..3
(-5325 3800);
FORCEPROP 2 LAST $XR0 44 
J 0
(-5111 3800);
DISPLAY 0.638298 (-5111 3800);
PAINT MONO (-5111 3800);
FORCEPROP 2 LAST PATH I76
J 0
(-5100 3850);
DISPLAY 1.021277 (-5100 3850);
DISPLAY INVISIBLE (-5100 3850);
FORCEPROP 1 LAST COMMENT_BODY TRUE
J 0
(-5375 3700);
DISPLAY 0.872340 (-5375 3700);
PAINT GREEN (-5375 3700);
DISPLAY INVISIBLE (-5375 3700);
FORCEPROP 1 LAST OFFPAGE TRUE
J 0
(-5000 3675);
DISPLAY 0.872340 (-5000 3675);
PAINT GREEN (-5000 3675);
DISPLAY INVISIBLE (-5000 3675);
FORCEPROP 2 LAST CDS_LIB mstr_standard
J 0
(-5325 3800);
DISPLAY 0.723404 (-5325 3800);
PAINT MONO (-5325 3800);
DISPLAY INVISIBLE (-5325 3800);
FORCEADD TAP..1
R 2
(-7650 4000);
FORCEPROP 3 LASTPIN (-7600 4000) SIG_NAME M_H_CPU1_SA_CB<7>
J 0
(-7590 4010);
DISPLAY 0.659574 (-7590 4010);
PAINT MONO (-7590 4010);
DISPLAY INVISIBLE (-7590 4010);
FORCEPROP 1 LASTPIN (-7600 4000) BN 7
J 2
(-7588 4008);
DISPLAY 0.489362 (-7588 4008);
PAINT GREEN (-7588 4008);
FORCEPROP 2 LAST CDS_LIB mstr_standard
J 0
(-7650 4000);
DISPLAY 0.723404 (-7650 4000);
PAINT MONO (-7650 4000);
DISPLAY INVISIBLE (-7650 4000);
FORCEPROP 1 LAST BODY_TYPE PLUMBING
J 2
(-7650 4050);
DISPLAY 0.872340 (-7650 4050);
PAINT GREEN (-7650 4050);
DISPLAY INVISIBLE (-7650 4050);
FORCEPROP 1 LAST HDL_TAP TRUE
J 2
(-7975 3875);
DISPLAY 0.872340 (-7975 3875);
DISPLAY INVISIBLE (-7975 3875);
FORCEPROP 1 LAST PATH I77
J 2
(-7648 4000);
DISPLAY 0.872340 (-7648 4000);
PAINT GREEN (-7648 4000);
DISPLAY INVISIBLE (-7648 4000);
FORCEADD TAP..1
R 2
(-7650 3950);
FORCEPROP 3 LASTPIN (-7600 3950) SIG_NAME M_H_CPU1_SA_CB<6>
J 0
(-7590 3960);
DISPLAY 0.659574 (-7590 3960);
PAINT MONO (-7590 3960);
DISPLAY INVISIBLE (-7590 3960);
FORCEPROP 1 LASTPIN (-7600 3950) BN 6
J 2
(-7588 3958);
DISPLAY 0.489362 (-7588 3958);
PAINT GREEN (-7588 3958);
FORCEPROP 2 LAST CDS_LIB mstr_standard
J 0
(-7650 3950);
DISPLAY 0.723404 (-7650 3950);
PAINT MONO (-7650 3950);
DISPLAY INVISIBLE (-7650 3950);
FORCEPROP 1 LAST BODY_TYPE PLUMBING
J 2
(-7650 4000);
DISPLAY 0.872340 (-7650 4000);
PAINT GREEN (-7650 4000);
DISPLAY INVISIBLE (-7650 4000);
FORCEPROP 1 LAST HDL_TAP TRUE
J 2
(-7975 3825);
DISPLAY 0.872340 (-7975 3825);
DISPLAY INVISIBLE (-7975 3825);
FORCEPROP 1 LAST PATH I78
J 2
(-7648 3950);
DISPLAY 0.872340 (-7648 3950);
PAINT GREEN (-7648 3950);
DISPLAY INVISIBLE (-7648 3950);
FORCEADD TAP..1
R 2
(-7650 3900);
FORCEPROP 3 LASTPIN (-7600 3900) SIG_NAME M_H_CPU1_SA_CB<5>
J 0
(-7590 3910);
DISPLAY 0.659574 (-7590 3910);
PAINT MONO (-7590 3910);
DISPLAY INVISIBLE (-7590 3910);
FORCEPROP 1 LASTPIN (-7600 3900) BN 5
J 2
(-7588 3908);
DISPLAY 0.489362 (-7588 3908);
PAINT GREEN (-7588 3908);
FORCEPROP 2 LAST CDS_LIB mstr_standard
J 0
(-7650 3900);
DISPLAY 0.723404 (-7650 3900);
PAINT MONO (-7650 3900);
DISPLAY INVISIBLE (-7650 3900);
FORCEPROP 1 LAST BODY_TYPE PLUMBING
J 2
(-7650 3950);
DISPLAY 0.872340 (-7650 3950);
PAINT GREEN (-7650 3950);
DISPLAY INVISIBLE (-7650 3950);
FORCEPROP 1 LAST HDL_TAP TRUE
J 2
(-7975 3775);
DISPLAY 0.872340 (-7975 3775);
DISPLAY INVISIBLE (-7975 3775);
FORCEPROP 1 LAST PATH I79
J 2
(-7648 3900);
DISPLAY 0.872340 (-7648 3900);
PAINT GREEN (-7648 3900);
DISPLAY INVISIBLE (-7648 3900);
FORCEADD OFFPAGE..1
(-8100 3100);
FORCEPROP 2 LAST $XR0 44 
J 0
(-8321 3100);
DISPLAY 0.638298 (-8321 3100);
PAINT MONO (-8321 3100);
FORCEPROP 2 LAST PATH I8
J 0
(-8300 3150);
DISPLAY 1.021277 (-8300 3150);
DISPLAY INVISIBLE (-8300 3150);
FORCEPROP 1 LAST COMMENT_BODY TRUE
J 0
(-7975 3000);
DISPLAY 0.872340 (-7975 3000);
PAINT GREEN (-7975 3000);
DISPLAY INVISIBLE (-7975 3000);
FORCEPROP 1 LAST OFFPAGE TRUE
J 0
(-7775 2975);
DISPLAY 0.872340 (-7775 2975);
PAINT GREEN (-7775 2975);
DISPLAY INVISIBLE (-7775 2975);
FORCEPROP 2 LAST CDS_LIB mstr_standard
J 0
(-8100 3100);
DISPLAY 0.808511 (-8100 3100);
DISPLAY INVISIBLE (-8100 3100);
FORCEADD TAP..1
R 2
(-7650 4850);
FORCEPROP 3 LASTPIN (-7600 4850) SIG_NAME M_H_CPU1_SB_CA<3>
J 0
(-7590 4860);
DISPLAY 0.659574 (-7590 4860);
PAINT MONO (-7590 4860);
DISPLAY INVISIBLE (-7590 4860);
FORCEPROP 1 LASTPIN (-7600 4850) BN 3
J 2
(-7588 4858);
DISPLAY 0.489362 (-7588 4858);
PAINT GREEN (-7588 4858);
FORCEPROP 2 LAST CDS_LIB mstr_standard
J 0
(-7650 4850);
DISPLAY 0.723404 (-7650 4850);
PAINT MONO (-7650 4850);
DISPLAY INVISIBLE (-7650 4850);
FORCEPROP 1 LAST BODY_TYPE PLUMBING
J 2
(-7650 4900);
DISPLAY 0.872340 (-7650 4900);
PAINT GREEN (-7650 4900);
DISPLAY INVISIBLE (-7650 4900);
FORCEPROP 1 LAST HDL_TAP TRUE
J 2
(-7975 4725);
DISPLAY 0.872340 (-7975 4725);
DISPLAY INVISIBLE (-7975 4725);
FORCEPROP 1 LAST PATH I80
J 2
(-7648 4850);
DISPLAY 0.872340 (-7648 4850);
PAINT GREEN (-7648 4850);
DISPLAY INVISIBLE (-7648 4850);
FORCEADD TAP..1
R 2
(-7650 4800);
FORCEPROP 3 LASTPIN (-7600 4800) SIG_NAME M_H_CPU1_SB_CA<2>
J 0
(-7590 4810);
DISPLAY 0.659574 (-7590 4810);
PAINT MONO (-7590 4810);
DISPLAY INVISIBLE (-7590 4810);
FORCEPROP 1 LASTPIN (-7600 4800) BN 2
J 2
(-7588 4808);
DISPLAY 0.489362 (-7588 4808);
PAINT GREEN (-7588 4808);
FORCEPROP 2 LAST CDS_LIB mstr_standard
J 0
(-7650 4800);
DISPLAY 0.723404 (-7650 4800);
PAINT MONO (-7650 4800);
DISPLAY INVISIBLE (-7650 4800);
FORCEPROP 1 LAST BODY_TYPE PLUMBING
J 2
(-7650 4850);
DISPLAY 0.872340 (-7650 4850);
PAINT GREEN (-7650 4850);
DISPLAY INVISIBLE (-7650 4850);
FORCEPROP 1 LAST HDL_TAP TRUE
J 2
(-7975 4675);
DISPLAY 0.872340 (-7975 4675);
DISPLAY INVISIBLE (-7975 4675);
FORCEPROP 1 LAST PATH I81
J 2
(-7648 4800);
DISPLAY 0.872340 (-7648 4800);
PAINT GREEN (-7648 4800);
DISPLAY INVISIBLE (-7648 4800);
FORCEADD TAP..1
R 2
(-7650 4750);
FORCEPROP 3 LASTPIN (-7600 4750) SIG_NAME M_H_CPU1_SB_CA<1>
J 0
(-7590 4760);
DISPLAY 0.659574 (-7590 4760);
PAINT MONO (-7590 4760);
DISPLAY INVISIBLE (-7590 4760);
FORCEPROP 1 LASTPIN (-7600 4750) BN 1
J 2
(-7588 4758);
DISPLAY 0.489362 (-7588 4758);
PAINT GREEN (-7588 4758);
FORCEPROP 2 LAST CDS_LIB mstr_standard
J 0
(-7650 4750);
DISPLAY 0.723404 (-7650 4750);
PAINT MONO (-7650 4750);
DISPLAY INVISIBLE (-7650 4750);
FORCEPROP 1 LAST BODY_TYPE PLUMBING
J 2
(-7650 4800);
DISPLAY 0.872340 (-7650 4800);
PAINT GREEN (-7650 4800);
DISPLAY INVISIBLE (-7650 4800);
FORCEPROP 1 LAST HDL_TAP TRUE
J 2
(-7975 4625);
DISPLAY 0.872340 (-7975 4625);
DISPLAY INVISIBLE (-7975 4625);
FORCEPROP 1 LAST PATH I82
J 2
(-7648 4750);
DISPLAY 0.872340 (-7648 4750);
PAINT GREEN (-7648 4750);
DISPLAY INVISIBLE (-7648 4750);
FORCEADD TAP..1
R 2
(-7650 4700);
FORCEPROP 3 LASTPIN (-7600 4700) SIG_NAME M_H_CPU1_SB_CA<0>
J 0
(-7590 4710);
DISPLAY 0.659574 (-7590 4710);
PAINT MONO (-7590 4710);
DISPLAY INVISIBLE (-7590 4710);
FORCEPROP 1 LASTPIN (-7600 4700) BN 0
J 2
(-7588 4708);
DISPLAY 0.489362 (-7588 4708);
PAINT GREEN (-7588 4708);
FORCEPROP 2 LAST CDS_LIB mstr_standard
J 0
(-7650 4700);
DISPLAY 0.723404 (-7650 4700);
PAINT MONO (-7650 4700);
DISPLAY INVISIBLE (-7650 4700);
FORCEPROP 1 LAST BODY_TYPE PLUMBING
J 2
(-7650 4750);
DISPLAY 0.872340 (-7650 4750);
PAINT GREEN (-7650 4750);
DISPLAY INVISIBLE (-7650 4750);
FORCEPROP 1 LAST HDL_TAP TRUE
J 2
(-7975 4575);
DISPLAY 0.872340 (-7975 4575);
DISPLAY INVISIBLE (-7975 4575);
FORCEPROP 1 LAST PATH I83
J 2
(-7648 4700);
DISPLAY 0.872340 (-7648 4700);
PAINT GREEN (-7648 4700);
DISPLAY INVISIBLE (-7648 4700);
FORCEADD TAP..1
R 2
(-7650 4900);
FORCEPROP 3 LASTPIN (-7600 4900) SIG_NAME M_H_CPU1_SB_CA<4>
J 0
(-7590 4910);
DISPLAY 0.659574 (-7590 4910);
PAINT MONO (-7590 4910);
DISPLAY INVISIBLE (-7590 4910);
FORCEPROP 1 LASTPIN (-7600 4900) BN 4
J 2
(-7588 4908);
DISPLAY 0.489362 (-7588 4908);
PAINT GREEN (-7588 4908);
FORCEPROP 2 LAST CDS_LIB mstr_standard
J 0
(-7650 4900);
DISPLAY 0.723404 (-7650 4900);
PAINT MONO (-7650 4900);
DISPLAY INVISIBLE (-7650 4900);
FORCEPROP 1 LAST BODY_TYPE PLUMBING
J 2
(-7650 4950);
DISPLAY 0.872340 (-7650 4950);
PAINT GREEN (-7650 4950);
DISPLAY INVISIBLE (-7650 4950);
FORCEPROP 1 LAST HDL_TAP TRUE
J 2
(-7975 4775);
DISPLAY 0.872340 (-7975 4775);
DISPLAY INVISIBLE (-7975 4775);
FORCEPROP 1 LAST PATH I84
J 2
(-7648 4900);
DISPLAY 0.872340 (-7648 4900);
PAINT GREEN (-7648 4900);
DISPLAY INVISIBLE (-7648 4900);
FORCEADD TAP..1
R 2
(-7650 4950);
FORCEPROP 3 LASTPIN (-7600 4950) SIG_NAME M_H_CPU1_SB_CA<5>
J 0
(-7590 4960);
DISPLAY 0.659574 (-7590 4960);
PAINT MONO (-7590 4960);
DISPLAY INVISIBLE (-7590 4960);
FORCEPROP 1 LASTPIN (-7600 4950) BN 5
J 2
(-7588 4958);
DISPLAY 0.489362 (-7588 4958);
PAINT GREEN (-7588 4958);
FORCEPROP 2 LAST CDS_LIB mstr_standard
J 0
(-7650 4950);
DISPLAY 0.723404 (-7650 4950);
PAINT MONO (-7650 4950);
DISPLAY INVISIBLE (-7650 4950);
FORCEPROP 1 LAST BODY_TYPE PLUMBING
J 2
(-7650 5000);
DISPLAY 0.872340 (-7650 5000);
PAINT GREEN (-7650 5000);
DISPLAY INVISIBLE (-7650 5000);
FORCEPROP 1 LAST HDL_TAP TRUE
J 2
(-7975 4825);
DISPLAY 0.872340 (-7975 4825);
DISPLAY INVISIBLE (-7975 4825);
FORCEPROP 1 LAST PATH I85
J 2
(-7648 4950);
DISPLAY 0.872340 (-7648 4950);
PAINT GREEN (-7648 4950);
DISPLAY INVISIBLE (-7648 4950);
FORCEADD TAP..1
R 2
(-7650 5000);
FORCEPROP 3 LASTPIN (-7600 5000) SIG_NAME M_H_CPU1_SB_CA<6>
J 0
(-7590 5010);
DISPLAY 0.659574 (-7590 5010);
PAINT MONO (-7590 5010);
DISPLAY INVISIBLE (-7590 5010);
FORCEPROP 1 LASTPIN (-7600 5000) BN 6
J 2
(-7588 5008);
DISPLAY 0.489362 (-7588 5008);
PAINT GREEN (-7588 5008);
FORCEPROP 2 LAST CDS_LIB mstr_standard
J 0
(-7650 5000);
DISPLAY 0.723404 (-7650 5000);
PAINT MONO (-7650 5000);
DISPLAY INVISIBLE (-7650 5000);
FORCEPROP 1 LAST BODY_TYPE PLUMBING
J 2
(-7650 5050);
DISPLAY 0.872340 (-7650 5050);
PAINT GREEN (-7650 5050);
DISPLAY INVISIBLE (-7650 5050);
FORCEPROP 1 LAST HDL_TAP TRUE
J 2
(-7975 4875);
DISPLAY 0.872340 (-7975 4875);
DISPLAY INVISIBLE (-7975 4875);
FORCEPROP 1 LAST PATH I86
J 2
(-7648 5000);
DISPLAY 0.872340 (-7648 5000);
PAINT GREEN (-7648 5000);
DISPLAY INVISIBLE (-7648 5000);
FORCEADD TAP..1
R 2
(-7650 5150);
FORCEPROP 3 LASTPIN (-7600 5150) SIG_NAME M_H_CPU1_SA_CA<1>
J 0
(-7590 5160);
DISPLAY 0.659574 (-7590 5160);
PAINT MONO (-7590 5160);
DISPLAY INVISIBLE (-7590 5160);
FORCEPROP 1 LASTPIN (-7600 5150) BN 1
J 2
(-7588 5158);
DISPLAY 0.489362 (-7588 5158);
PAINT GREEN (-7588 5158);
FORCEPROP 2 LAST CDS_LIB mstr_standard
J 0
(-7650 5150);
DISPLAY 0.723404 (-7650 5150);
PAINT MONO (-7650 5150);
DISPLAY INVISIBLE (-7650 5150);
FORCEPROP 1 LAST BODY_TYPE PLUMBING
J 2
(-7650 5200);
DISPLAY 0.872340 (-7650 5200);
PAINT GREEN (-7650 5200);
DISPLAY INVISIBLE (-7650 5200);
FORCEPROP 1 LAST HDL_TAP TRUE
J 2
(-7975 5025);
DISPLAY 0.872340 (-7975 5025);
DISPLAY INVISIBLE (-7975 5025);
FORCEPROP 1 LAST PATH I87
J 2
(-7648 5150);
DISPLAY 0.872340 (-7648 5150);
PAINT GREEN (-7648 5150);
DISPLAY INVISIBLE (-7648 5150);
FORCEADD TAP..1
R 2
(-7650 5100);
FORCEPROP 3 LASTPIN (-7600 5100) SIG_NAME M_H_CPU1_SA_CA<0>
J 0
(-7590 5110);
DISPLAY 0.659574 (-7590 5110);
PAINT MONO (-7590 5110);
DISPLAY INVISIBLE (-7590 5110);
FORCEPROP 1 LASTPIN (-7600 5100) BN 0
J 2
(-7588 5108);
DISPLAY 0.489362 (-7588 5108);
PAINT GREEN (-7588 5108);
FORCEPROP 2 LAST CDS_LIB mstr_standard
J 0
(-7650 5100);
DISPLAY 0.723404 (-7650 5100);
PAINT MONO (-7650 5100);
DISPLAY INVISIBLE (-7650 5100);
FORCEPROP 1 LAST BODY_TYPE PLUMBING
J 2
(-7650 5150);
DISPLAY 0.872340 (-7650 5150);
PAINT GREEN (-7650 5150);
DISPLAY INVISIBLE (-7650 5150);
FORCEPROP 1 LAST HDL_TAP TRUE
J 2
(-7975 4975);
DISPLAY 0.872340 (-7975 4975);
DISPLAY INVISIBLE (-7975 4975);
FORCEPROP 1 LAST PATH I88
J 2
(-7648 5100);
DISPLAY 0.872340 (-7648 5100);
PAINT GREEN (-7648 5100);
DISPLAY INVISIBLE (-7648 5100);
FORCEADD TAP..1
R 2
(-7650 5200);
FORCEPROP 3 LASTPIN (-7600 5200) SIG_NAME M_H_CPU1_SA_CA<2>
J 0
(-7590 5210);
DISPLAY 0.659574 (-7590 5210);
PAINT MONO (-7590 5210);
DISPLAY INVISIBLE (-7590 5210);
FORCEPROP 1 LASTPIN (-7600 5200) BN 2
J 2
(-7588 5208);
DISPLAY 0.489362 (-7588 5208);
PAINT GREEN (-7588 5208);
FORCEPROP 2 LAST CDS_LIB mstr_standard
J 0
(-7650 5200);
DISPLAY 0.723404 (-7650 5200);
PAINT MONO (-7650 5200);
DISPLAY INVISIBLE (-7650 5200);
FORCEPROP 1 LAST BODY_TYPE PLUMBING
J 2
(-7650 5250);
DISPLAY 0.872340 (-7650 5250);
PAINT GREEN (-7650 5250);
DISPLAY INVISIBLE (-7650 5250);
FORCEPROP 1 LAST HDL_TAP TRUE
J 2
(-7975 5075);
DISPLAY 0.872340 (-7975 5075);
DISPLAY INVISIBLE (-7975 5075);
FORCEPROP 1 LAST PATH I89
J 2
(-7648 5200);
DISPLAY 0.872340 (-7648 5200);
PAINT GREEN (-7648 5200);
DISPLAY INVISIBLE (-7648 5200);
FORCEADD VCC_CORE..1
(-8475 3425);
FORCEPROP 3 LASTPIN (-8475 3375) SIG_NAME P3V3_STBY\g
J 0
(-8465 3385);
DISPLAY 0.659574 (-8465 3385);
PAINT MONO (-8465 3385);
DISPLAY INVISIBLE (-8465 3385);
FORCEPROP 1 LAST HDL_POWER P3V3_STBY
J 1
(-8475 3475);
DISPLAY 0.489362 (-8475 3475);
PAINT GREEN (-8475 3475);
FORCEPROP 2 LAST CDS_LIB mstr_symbols
J 0
(-8475 3425);
PAINT MONO (-8475 3425);
DISPLAY INVISIBLE (-8475 3425);
FORCEPROP 1 LAST PATH I9
J 0
(-8425 3450);
DISPLAY 0.872340 (-8425 3450);
PAINT AQUA (-8425 3450);
DISPLAY INVISIBLE (-8425 3450);
FORCEPROP 0 LAST VOLTAGE 3.3
J 0
(-8750 3575);
DISPLAY 1.021277 (-8750 3575);
PAINT SKYBLUE (-8750 3575);
DISPLAY INVISIBLE (-8750 3575);
FORCEPROP 2 LAST ROOM PVCCINFAON_CPU1_CTRL
J 0
(-8475 3525);
DISPLAY 0.808511 (-8475 3525);
PAINT RED (-8475 3525);
DISPLAY INVISIBLE (-8475 3525);
FORCEADD TAP..1
R 2
(-7650 5250);
FORCEPROP 3 LASTPIN (-7600 5250) SIG_NAME M_H_CPU1_SA_CA<3>
J 0
(-7590 5260);
DISPLAY 0.659574 (-7590 5260);
PAINT MONO (-7590 5260);
DISPLAY INVISIBLE (-7590 5260);
FORCEPROP 1 LASTPIN (-7600 5250) BN 3
J 2
(-7588 5258);
DISPLAY 0.489362 (-7588 5258);
PAINT GREEN (-7588 5258);
FORCEPROP 2 LAST CDS_LIB mstr_standard
J 0
(-7650 5250);
DISPLAY 0.723404 (-7650 5250);
PAINT MONO (-7650 5250);
DISPLAY INVISIBLE (-7650 5250);
FORCEPROP 1 LAST BODY_TYPE PLUMBING
J 2
(-7650 5300);
DISPLAY 0.872340 (-7650 5300);
PAINT GREEN (-7650 5300);
DISPLAY INVISIBLE (-7650 5300);
FORCEPROP 1 LAST HDL_TAP TRUE
J 2
(-7975 5125);
DISPLAY 0.872340 (-7975 5125);
DISPLAY INVISIBLE (-7975 5125);
FORCEPROP 1 LAST PATH I90
J 2
(-7648 5250);
DISPLAY 0.872340 (-7648 5250);
PAINT GREEN (-7648 5250);
DISPLAY INVISIBLE (-7648 5250);
FORCEADD TAP..1
R 2
(-7650 5300);
FORCEPROP 3 LASTPIN (-7600 5300) SIG_NAME M_H_CPU1_SA_CA<4>
J 0
(-7590 5310);
DISPLAY 0.659574 (-7590 5310);
PAINT MONO (-7590 5310);
DISPLAY INVISIBLE (-7590 5310);
FORCEPROP 1 LASTPIN (-7600 5300) BN 4
J 2
(-7588 5308);
DISPLAY 0.489362 (-7588 5308);
PAINT GREEN (-7588 5308);
FORCEPROP 2 LAST CDS_LIB mstr_standard
J 0
(-7650 5300);
DISPLAY 0.723404 (-7650 5300);
PAINT MONO (-7650 5300);
DISPLAY INVISIBLE (-7650 5300);
FORCEPROP 1 LAST BODY_TYPE PLUMBING
J 2
(-7650 5350);
DISPLAY 0.872340 (-7650 5350);
PAINT GREEN (-7650 5350);
DISPLAY INVISIBLE (-7650 5350);
FORCEPROP 1 LAST HDL_TAP TRUE
J 2
(-7975 5175);
DISPLAY 0.872340 (-7975 5175);
DISPLAY INVISIBLE (-7975 5175);
FORCEPROP 1 LAST PATH I91
J 2
(-7648 5300);
DISPLAY 0.872340 (-7648 5300);
PAINT GREEN (-7648 5300);
DISPLAY INVISIBLE (-7648 5300);
FORCEADD TAP..1
R 2
(-7650 5400);
FORCEPROP 3 LASTPIN (-7600 5400) SIG_NAME M_H_CPU1_SA_CA<6>
J 0
(-7590 5410);
DISPLAY 0.659574 (-7590 5410);
PAINT MONO (-7590 5410);
DISPLAY INVISIBLE (-7590 5410);
FORCEPROP 1 LASTPIN (-7600 5400) BN 6
J 2
(-7588 5408);
DISPLAY 0.489362 (-7588 5408);
PAINT GREEN (-7588 5408);
FORCEPROP 2 LAST CDS_LIB mstr_standard
J 0
(-7650 5400);
DISPLAY 0.723404 (-7650 5400);
PAINT MONO (-7650 5400);
DISPLAY INVISIBLE (-7650 5400);
FORCEPROP 1 LAST BODY_TYPE PLUMBING
J 2
(-7650 5450);
DISPLAY 0.872340 (-7650 5450);
PAINT GREEN (-7650 5450);
DISPLAY INVISIBLE (-7650 5450);
FORCEPROP 1 LAST HDL_TAP TRUE
J 2
(-7975 5275);
DISPLAY 0.872340 (-7975 5275);
DISPLAY INVISIBLE (-7975 5275);
FORCEPROP 1 LAST PATH I92
J 2
(-7648 5400);
DISPLAY 0.872340 (-7648 5400);
PAINT GREEN (-7648 5400);
DISPLAY INVISIBLE (-7648 5400);
FORCEADD TAP..1
R 2
(-7650 5350);
FORCEPROP 3 LASTPIN (-7600 5350) SIG_NAME M_H_CPU1_SA_CA<5>
J 0
(-7590 5360);
DISPLAY 0.659574 (-7590 5360);
PAINT MONO (-7590 5360);
DISPLAY INVISIBLE (-7590 5360);
FORCEPROP 1 LASTPIN (-7600 5350) BN 5
J 2
(-7588 5358);
DISPLAY 0.489362 (-7588 5358);
PAINT GREEN (-7588 5358);
FORCEPROP 2 LAST CDS_LIB mstr_standard
J 0
(-7650 5350);
DISPLAY 0.723404 (-7650 5350);
PAINT MONO (-7650 5350);
DISPLAY INVISIBLE (-7650 5350);
FORCEPROP 1 LAST BODY_TYPE PLUMBING
J 2
(-7650 5400);
DISPLAY 0.872340 (-7650 5400);
PAINT GREEN (-7650 5400);
DISPLAY INVISIBLE (-7650 5400);
FORCEPROP 1 LAST HDL_TAP TRUE
J 2
(-7975 5225);
DISPLAY 0.872340 (-7975 5225);
DISPLAY INVISIBLE (-7975 5225);
FORCEPROP 1 LAST PATH I93
J 2
(-7648 5350);
DISPLAY 0.872340 (-7648 5350);
PAINT GREEN (-7648 5350);
DISPLAY INVISIBLE (-7648 5350);
FORCEADD TAP..1
(-5950 3900);
FORCEPROP 3 LASTPIN (-6000 3900) SIG_NAME M_H_CPU1_SA_DQ<1>
J 0
(-5990 3910);
DISPLAY 0.659574 (-5990 3910);
PAINT MONO (-5990 3910);
DISPLAY INVISIBLE (-5990 3910);
FORCEPROP 1 LASTPIN (-6000 3900) BN 1
J 0
(-6012 3908);
DISPLAY 0.489362 (-6012 3908);
PAINT GREEN (-6012 3908);
FORCEPROP 2 LAST CDS_LIB mstr_standard
J 0
(-5950 3900);
DISPLAY 0.723404 (-5950 3900);
PAINT MONO (-5950 3900);
DISPLAY INVISIBLE (-5950 3900);
FORCEPROP 1 LAST BODY_TYPE PLUMBING
J 0
(-5950 3950);
DISPLAY 0.872340 (-5950 3950);
PAINT GREEN (-5950 3950);
DISPLAY INVISIBLE (-5950 3950);
FORCEPROP 1 LAST HDL_TAP TRUE
J 0
(-5625 3775);
DISPLAY 0.872340 (-5625 3775);
DISPLAY INVISIBLE (-5625 3775);
FORCEPROP 1 LAST PATH I94
J 0
(-5952 3900);
DISPLAY 0.872340 (-5952 3900);
PAINT GREEN (-5952 3900);
DISPLAY INVISIBLE (-5952 3900);
FORCEADD TAP..1
(-5950 3950);
FORCEPROP 3 LASTPIN (-6000 3950) SIG_NAME M_H_CPU1_SA_DQ<2>
J 0
(-5990 3960);
DISPLAY 0.659574 (-5990 3960);
PAINT MONO (-5990 3960);
DISPLAY INVISIBLE (-5990 3960);
FORCEPROP 1 LASTPIN (-6000 3950) BN 2
J 0
(-6012 3958);
DISPLAY 0.489362 (-6012 3958);
PAINT GREEN (-6012 3958);
FORCEPROP 2 LAST CDS_LIB mstr_standard
J 0
(-5950 3950);
DISPLAY 0.723404 (-5950 3950);
PAINT MONO (-5950 3950);
DISPLAY INVISIBLE (-5950 3950);
FORCEPROP 1 LAST BODY_TYPE PLUMBING
J 0
(-5950 4000);
DISPLAY 0.872340 (-5950 4000);
PAINT GREEN (-5950 4000);
DISPLAY INVISIBLE (-5950 4000);
FORCEPROP 1 LAST HDL_TAP TRUE
J 0
(-5625 3825);
DISPLAY 0.872340 (-5625 3825);
DISPLAY INVISIBLE (-5625 3825);
FORCEPROP 1 LAST PATH I95
J 0
(-5952 3950);
DISPLAY 0.872340 (-5952 3950);
PAINT GREEN (-5952 3950);
DISPLAY INVISIBLE (-5952 3950);
FORCEADD TAP..1
(-5950 4000);
FORCEPROP 3 LASTPIN (-6000 4000) SIG_NAME M_H_CPU1_SA_DQ<3>
J 0
(-5990 4010);
DISPLAY 0.659574 (-5990 4010);
PAINT MONO (-5990 4010);
DISPLAY INVISIBLE (-5990 4010);
FORCEPROP 1 LASTPIN (-6000 4000) BN 3
J 0
(-6012 4008);
DISPLAY 0.489362 (-6012 4008);
PAINT GREEN (-6012 4008);
FORCEPROP 2 LAST CDS_LIB mstr_standard
J 0
(-5950 4000);
DISPLAY 0.723404 (-5950 4000);
PAINT MONO (-5950 4000);
DISPLAY INVISIBLE (-5950 4000);
FORCEPROP 1 LAST BODY_TYPE PLUMBING
J 0
(-5950 4050);
DISPLAY 0.872340 (-5950 4050);
PAINT GREEN (-5950 4050);
DISPLAY INVISIBLE (-5950 4050);
FORCEPROP 1 LAST HDL_TAP TRUE
J 0
(-5625 3875);
DISPLAY 0.872340 (-5625 3875);
DISPLAY INVISIBLE (-5625 3875);
FORCEPROP 1 LAST PATH I96
J 0
(-5952 4000);
DISPLAY 0.872340 (-5952 4000);
PAINT GREEN (-5952 4000);
DISPLAY INVISIBLE (-5952 4000);
FORCEADD TAP..1
(-5950 4150);
FORCEPROP 3 LASTPIN (-6000 4150) SIG_NAME M_H_CPU1_SA_DQ<6>
J 0
(-5990 4160);
DISPLAY 0.659574 (-5990 4160);
PAINT MONO (-5990 4160);
DISPLAY INVISIBLE (-5990 4160);
FORCEPROP 1 LASTPIN (-6000 4150) BN 6
J 0
(-6012 4158);
DISPLAY 0.489362 (-6012 4158);
PAINT GREEN (-6012 4158);
FORCEPROP 2 LAST CDS_LIB mstr_standard
J 0
(-5950 4150);
DISPLAY 0.723404 (-5950 4150);
PAINT MONO (-5950 4150);
DISPLAY INVISIBLE (-5950 4150);
FORCEPROP 1 LAST BODY_TYPE PLUMBING
J 0
(-5950 4200);
DISPLAY 0.872340 (-5950 4200);
PAINT GREEN (-5950 4200);
DISPLAY INVISIBLE (-5950 4200);
FORCEPROP 1 LAST HDL_TAP TRUE
J 0
(-5625 4025);
DISPLAY 0.872340 (-5625 4025);
DISPLAY INVISIBLE (-5625 4025);
FORCEPROP 1 LAST PATH I97
J 0
(-5952 4150);
DISPLAY 0.872340 (-5952 4150);
PAINT GREEN (-5952 4150);
DISPLAY INVISIBLE (-5952 4150);
FORCEADD TAP..1
(-5950 4050);
FORCEPROP 3 LASTPIN (-6000 4050) SIG_NAME M_H_CPU1_SA_DQ<4>
J 0
(-5990 4060);
DISPLAY 0.659574 (-5990 4060);
PAINT MONO (-5990 4060);
DISPLAY INVISIBLE (-5990 4060);
FORCEPROP 1 LASTPIN (-6000 4050) BN 4
J 0
(-6012 4058);
DISPLAY 0.489362 (-6012 4058);
PAINT GREEN (-6012 4058);
FORCEPROP 2 LAST CDS_LIB mstr_standard
J 0
(-5950 4050);
DISPLAY 0.723404 (-5950 4050);
PAINT MONO (-5950 4050);
DISPLAY INVISIBLE (-5950 4050);
FORCEPROP 1 LAST BODY_TYPE PLUMBING
J 0
(-5950 4100);
DISPLAY 0.872340 (-5950 4100);
PAINT GREEN (-5950 4100);
DISPLAY INVISIBLE (-5950 4100);
FORCEPROP 1 LAST HDL_TAP TRUE
J 0
(-5625 3925);
DISPLAY 0.872340 (-5625 3925);
DISPLAY INVISIBLE (-5625 3925);
FORCEPROP 1 LAST PATH I98
J 0
(-5952 4050);
DISPLAY 0.872340 (-5952 4050);
PAINT GREEN (-5952 4050);
DISPLAY INVISIBLE (-5952 4050);
FORCEADD TAP..1
(-5950 4100);
FORCEPROP 3 LASTPIN (-6000 4100) SIG_NAME M_H_CPU1_SA_DQ<5>
J 0
(-5990 4110);
DISPLAY 0.659574 (-5990 4110);
PAINT MONO (-5990 4110);
DISPLAY INVISIBLE (-5990 4110);
FORCEPROP 1 LASTPIN (-6000 4100) BN 5
J 0
(-6012 4108);
DISPLAY 0.489362 (-6012 4108);
PAINT GREEN (-6012 4108);
FORCEPROP 2 LAST CDS_LIB mstr_standard
J 0
(-5950 4100);
DISPLAY 0.723404 (-5950 4100);
PAINT MONO (-5950 4100);
DISPLAY INVISIBLE (-5950 4100);
FORCEPROP 1 LAST BODY_TYPE PLUMBING
J 0
(-5950 4150);
DISPLAY 0.872340 (-5950 4150);
PAINT GREEN (-5950 4150);
DISPLAY INVISIBLE (-5950 4150);
FORCEPROP 1 LAST HDL_TAP TRUE
J 0
(-5625 3975);
DISPLAY 0.872340 (-5625 3975);
DISPLAY INVISIBLE (-5625 3975);
FORCEPROP 1 LAST PATH I99
J 0
(-5952 4100);
DISPLAY 0.872340 (-5952 4100);
PAINT GREEN (-5952 4100);
DISPLAY INVISIBLE (-5952 4100);
FORCEADD QUANTA_TITLE_BLOCK_C..1
(0 0);
FORCEPROP 0 LAST CDS_CON_LAST_MODIFIED Fri Mar 11 14:53:06 2022
J 0
(-1885 15);
DISPLAY INVISIBLE (-1885 15);
FORCEPROP 1 LAST CUSTOM_TXT_CDS <CON_LAST_MODIFIED>
J 0
(-1885 15);
DISPLAY 0.978723 (-1885 15);
FORCEPROP 2 LAST CUSTOM_TXT_CDS <XR_PAGE_TITLE>
J 0
(-7890 5250);
DISPLAY 0.638298 (-7890 5250);
PAINT PINK (-7890 5250);
DISPLAY INVISIBLE (-7890 5250);
FORCEPROP 1 LAST CUSTOM_TXT_CDS <NAME_2>
J 0
(-3175 50);
FORCEPROP 1 LAST CUSTOM_TXT_CDS <NAME_1>
J 0
(-3175 175);
FORCEPROP 1 LAST CUSTOM_TXT_CDS <Q_NUMBER>
J 0
(-1403 103);
DISPLAY 1.212766 (-1403 103);
FORCEPROP 1 LAST CUSTOM_TXT_CDS <Q_PROJ>
J 0
(-2382 102);
DISPLAY 1.212766 (-2382 102);
FORCEPROP 1 LAST CUSTOM_TXT_CDS <Q_REV>
J 0
(-184 103);
DISPLAY 1.212766 (-184 103);
FORCEPROP 1 LAST CUSTOM_TXT_CDS <CON_PAGE_NUM> OF <CON_TOTAL_PAGES>
J 0
(-446 18);
DISPLAY 0.978723 (-446 18);
FORCEPROP 1 LAST Q_TITLE DDR5 - CPU1 CHH
J 0
(-9366 26);
DISPLAY 2.446809 (-9366 26);
PAINT GREEN (-9366 26);
FORCEPROP 1 LAST Q_DEPT BU9
J 1
(-3763 49);
DISPLAY 1.957447 (-3763 49);
PAINT GREEN (-3763 49);
FORCEPROP 2 LAST PAGE_BORDER TRUE
J 0
(-7890 5250);
DISPLAY 0.638298 (-7890 5250);
PAINT PINK (-7890 5250);
DISPLAY INVISIBLE (-7890 5250);
FORCEPROP 1 LAST CDS_LMAN_SYM_OUTLINE -9475,6775,100,-125
J 0
(0 0);
DISPLAY 0.468085 (0 0);
PAINT GREEN (0 0);
DISPLAY INVISIBLE (0 0);
FORCEPROP 2 LAST CDS_LIB pure_quanta
J 0
(0 0);
DISPLAY INVISIBLE (0 0);
FORCEPROP 1 LAST COMMENT_BODY TRUE
J 0
(12 -13);
DISPLAY 0.978723 (12 -13);
PAINT GREEN (12 -13);
DISPLAY INVISIBLE (12 -13);
FORCEPROP 2 LAST CDS_XR_PAGE_TITLE CR-104 : @T6G_MB_LIB.T6G(SCH_1):PAGE104
J 0
(-7890 5250);
DISPLAY 0.638298 (-7890 5250);
PAINT PINK (-7890 5250);
DISPLAY INVISIBLE (-7890 5250);
FORCEADD DNS..2
(-8325 2300);
PAINT RED (-8325 2300);
FORCEPROP 2 LAST CDS_LIB mstr_misc
J 0
(-8325 2300);
DISPLAY INVISIBLE (-8325 2300);
FORCEPROP 1 LAST COMMENT_BODY TRUE
R 1
J 0
(-8250 2075);
DISPLAY 0.872340 (-8250 2075);
PAINT PEACH (-8250 2075);
DISPLAY INVISIBLE (-8250 2075);
WIRE 17 -1 (-5900 5450)(-5900 5425);
WIRE 17 -1 (-5900 5450)(-5375 5450);
FORCEPROP 2 LAST SIG_NAME M_H_CPU1_SA_DQ<31:0>
J 0
(-5835 5460);
DISPLAY 0.489362 (-5835 5460);
WIRE 17 -1 (-7700 4025)(-7700 3975);
WIRE 17 -1 (-7700 4025)(-7700 4050);
WIRE 17 -1 (-7700 3925)(-7700 3975);
WIRE 17 -1 (-7700 3925)(-7700 3875);
WIRE 17 -1 (-7700 4050)(-8200 4050);
FORCEPROP 2 LAST SIG_NAME M_H_CPU1_SA_CB<7:0>
J 0
(-8150 4060);
DISPLAY 0.489362 (-8150 4060);
WIRE 17 -1 (-7700 3825)(-7700 3875);
WIRE 17 -1 (-7700 3775)(-7700 3825);
WIRE 17 -1 (-7700 3725)(-7700 3775);
WIRE 17 -1 (-7700 3675)(-7700 3725);
WIRE 17 -1 (-7700 3575)(-7700 3525);
WIRE 17 -1 (-7700 3575)(-7700 3600);
WIRE 17 -1 (-7700 3475)(-7700 3525);
WIRE 17 -1 (-7700 3475)(-7700 3425);
WIRE 17 -1 (-7700 3600)(-8200 3600);
FORCEPROP 2 LAST SIG_NAME M_H_CPU1_SB_CB<7:0>
J 0
(-8150 3610);
DISPLAY 0.489362 (-8150 3610);
WIRE 17 -1 (-7700 5125)(-7700 5175);
WIRE 17 -1 (-7700 5175)(-7700 5225);
WIRE 17 -1 (-7700 5225)(-7700 5275);
WIRE 17 -1 (-7700 5275)(-7700 5325);
WIRE 17 -1 (-7700 5325)(-7700 5375);
WIRE 17 -1 (-7700 5375)(-7700 5425);
WIRE 17 -1 (-7700 5425)(-7700 5450);
WIRE 17 -1 (-7700 5450)(-8200 5450);
FORCEPROP 2 LAST SIG_NAME M_H_CPU1_SA_CA<6:0>
J 0
(-8185 5460);
DISPLAY 0.489362 (-8185 5460);
WIRE 17 -1 (-7700 4725)(-7700 4775);
WIRE 17 -1 (-7700 4775)(-7700 4825);
WIRE 17 -1 (-7700 4825)(-7700 4875);
WIRE 17 -1 (-7700 4875)(-7700 4925);
WIRE 17 -1 (-7700 4925)(-7700 4975);
WIRE 17 -1 (-7700 4975)(-7700 5025);
WIRE 17 -1 (-7700 5025)(-7700 5050);
WIRE 17 -1 (-7700 5050)(-8200 5050);
FORCEPROP 2 LAST SIG_NAME M_H_CPU1_SB_CA<6:0>
J 0
(-8185 5060);
DISPLAY 0.489362 (-8185 5060);
WIRE 17 -1 (-7700 3375)(-7700 3425);
WIRE 17 -1 (-7700 3325)(-7700 3375);
WIRE 17 -1 (-7700 3275)(-7700 3325);
WIRE 17 -1 (-7700 3225)(-7700 3275);
WIRE 17 -1 (-5900 5225)(-5900 5175);
WIRE 17 -1 (-5900 5275)(-5900 5225);
WIRE 17 -1 (-5900 5175)(-5900 5125);
WIRE 17 -1 (-5900 5125)(-5900 5075);
WIRE 17 -1 (-5900 5325)(-5900 5275);
WIRE 17 -1 (-5900 5375)(-5900 5325);
WIRE 17 -1 (-5900 5075)(-5900 5025);
WIRE 17 -1 (-5900 5025)(-5900 4975);
WIRE 17 -1 (-5900 5425)(-5900 5375);
WIRE 17 -1 (-5900 4975)(-5900 4925);
WIRE 17 -1 (-5900 4925)(-5900 4875);
WIRE 17 -1 (-5900 4875)(-5900 4825);
WIRE 17 -1 (-5900 4825)(-5900 4775);
WIRE 17 -1 (-5900 4775)(-5900 4725);
WIRE 17 -1 (-5900 4725)(-5900 4675);
WIRE 17 -1 (-5900 4625)(-5900 4675);
WIRE 17 -1 (-5900 4575)(-5900 4625);
WIRE 17 -1 (-5900 4525)(-5900 4575);
WIRE 17 -1 (-5900 4475)(-5900 4525);
WIRE 17 -1 (-5900 4475)(-5900 4425);
WIRE 17 -1 (-5900 4425)(-5900 4375);
WIRE 17 -1 (-5900 4375)(-5900 4325);
WIRE 17 -1 (-5900 4325)(-5900 4275);
WIRE 17 -1 (-5900 4275)(-5900 4225);
WIRE 17 -1 (-5900 4225)(-5900 4175);
WIRE 17 -1 (-5900 4175)(-5900 4125);
WIRE 17 -1 (-5900 4125)(-5900 4075);
WIRE 17 -1 (-5900 4025)(-5900 4075);
WIRE 17 -1 (-5900 3975)(-5900 4025);
WIRE 17 -1 (-5900 3925)(-5900 3975);
WIRE 17 -1 (-5900 3875)(-5900 3925);
WIRE 17 -1 (-5900 3800)(-5900 3775);
WIRE 17 -1 (-5900 3800)(-5375 3800);
FORCEPROP 2 LAST SIG_NAME M_H_CPU1_SB_DQ<31:0>
J 0
(-5835 3810);
DISPLAY 0.489362 (-5835 3810);
WIRE 17 -1 (-5900 3725)(-5900 3675);
WIRE 17 -1 (-5900 3775)(-5900 3725);
WIRE 17 -1 (-5900 3675)(-5900 3625);
WIRE 17 -1 (-5900 3625)(-5900 3575);
WIRE 17 -1 (-5900 3575)(-5900 3525);
WIRE 17 -1 (-5900 3525)(-5900 3475);
WIRE 17 -1 (-5900 3475)(-5900 3425);
WIRE 17 -1 (-5900 3425)(-5900 3375);
WIRE 17 -1 (-5900 3375)(-5900 3325);
WIRE 17 -1 (-5900 3325)(-5900 3275);
WIRE 17 -1 (-5900 3275)(-5900 3225);
WIRE 17 -1 (-5900 3225)(-5900 3175);
WIRE 17 -1 (-5900 3175)(-5900 3125);
WIRE 17 -1 (-5900 3125)(-5900 3075);
WIRE 17 -1 (-5900 3075)(-5900 3025);
WIRE 17 -1 (-5900 2975)(-5900 3025);
WIRE 17 -1 (-5900 2925)(-5900 2975);
WIRE 17 -1 (-5900 2875)(-5900 2925);
WIRE 17 -1 (-5900 2825)(-5900 2875);
WIRE 17 -1 (-5900 2825)(-5900 2775);
WIRE 17 -1 (-5900 2775)(-5900 2725);
WIRE 17 -1 (-5900 2725)(-5900 2675);
WIRE 17 -1 (-5900 2675)(-5900 2625);
WIRE 17 -1 (-5900 2625)(-5900 2575);
WIRE 17 -1 (-5900 2575)(-5900 2525);
WIRE 17 -1 (-5900 2525)(-5900 2475);
WIRE 17 -1 (-5900 2475)(-5900 2425);
WIRE 17 -1 (-5900 2375)(-5900 2425);
WIRE 17 -1 (-5900 2325)(-5900 2375);
WIRE 17 -1 (-5900 2275)(-5900 2325);
WIRE 17 -1 (-5900 2225)(-5900 2275);
WIRE 17 -1 (-3175 4200)(-3175 4100);
WIRE 17 -1 (-3175 4300)(-3175 4200);
WIRE 17 -1 (-3175 4100)(-3175 4000);
WIRE 17 -1 (-3175 3900)(-3175 4000);
WIRE 17 -1 (-3175 4400)(-3175 4300);
WIRE 17 -1 (-3175 4425)(-3175 4400);
WIRE 17 -1 (-3175 3800)(-3175 3900);
WIRE 17 -1 (-3175 3700)(-3175 3800);
WIRE 17 -1 (-3175 4425)(-2475 4425);
FORCEPROP 2 LAST SIG_NAME M_H_CPU1_SA_DQS_DN<9:0>
J 0
(-3110 4435);
DISPLAY 0.489362 (-3110 4435);
WIRE 17 -1 (-3375 4150)(-3375 4050);
WIRE 17 -1 (-3375 4250)(-3375 4150);
WIRE 17 -1 (-3375 3950)(-3375 4050);
WIRE 17 -1 (-3375 3850)(-3375 3950);
WIRE 17 -1 (-3375 4350)(-3375 4250);
WIRE 17 -1 (-3375 4450)(-3375 4350);
WIRE 17 -1 (-3375 3750)(-3375 3850);
WIRE 17 -1 (-3375 3750)(-3375 3650);
WIRE 17 -1 (-3375 4475)(-3375 4450);
WIRE 17 -1 (-3375 4475)(-2475 4475);
FORCEPROP 2 LAST SIG_NAME M_H_CPU1_SA_DQS_DP<9:0>
J 0
(-3110 4485);
DISPLAY 0.489362 (-3110 4485);
WIRE 17 -1 (-3375 3300)(-3375 3200);
WIRE 17 -1 (-3375 3400)(-3375 3300);
WIRE 17 -1 (-3375 3200)(-3375 3100);
WIRE 17 -1 (-3375 3100)(-3375 3000);
WIRE 17 -1 (-3375 3425)(-3375 3400);
WIRE 17 -1 (-3375 3425)(-2475 3425);
FORCEPROP 2 LAST SIG_NAME M_H_CPU1_SB_DQS_DP<9:0>
J 0
(-3110 3435);
DISPLAY 0.489362 (-3110 3435);
WIRE 17 -1 (-3175 3250)(-3175 3150);
WIRE 17 -1 (-3175 3350)(-3175 3250);
WIRE 17 -1 (-3175 3150)(-3175 3050);
WIRE 17 -1 (-3175 3050)(-3175 2950);
WIRE 17 -1 (-3175 3375)(-3175 3350);
WIRE 17 -1 (-3175 3375)(-2475 3375);
FORCEPROP 2 LAST SIG_NAME M_H_CPU1_SB_DQS_DN<9:0>
J 0
(-3110 3385);
DISPLAY 0.489362 (-3110 3385);
WIRE 17 -1 (-3375 2900)(-3375 3000);
WIRE 17 -1 (-3375 2800)(-3375 2900);
WIRE 17 -1 (-3375 2700)(-3375 2800);
WIRE 17 -1 (-3175 3600)(-3175 3500);
WIRE 17 -1 (-3175 3700)(-3175 3600);
WIRE 17 -1 (-3375 3650)(-3375 3550);
WIRE 17 -1 (-3175 2550)(-3175 2450);
WIRE 17 -1 (-3175 2650)(-3175 2550);
WIRE 17 -1 (-3175 2650)(-3175 2750);
WIRE 17 -1 (-3175 2750)(-3175 2850);
WIRE 17 -1 (-3175 2850)(-3175 2950);
WIRE 17 -1 (-3375 2600)(-3375 2500);
WIRE 17 -1 (-3375 2700)(-3375 2600);
WIRE 16 -1 (-6375 900)(-6375 975);
WIRE 16 -1 (-8575 3050)(-8575 3125);
WIRE 16 -1 (-8350 2400)(-8350 2425);
WIRE 16 -1 (-7800 2700)(-8225 2700);
FORCEPROP 2 LAST SIG_NAME I3C_SPD_DDRGL_CPU1_SCL
J 0
(-8260 2710);
DISPLAY 0.489362 (-8260 2710);
WIRE 16 -1 (-7400 2800)(-7500 2800);
FORCEPROP 2 LAST SIG_NAME I3C_SPD_DDRH_CPU1_SCL
J 0
(-7885 2810);
DISPLAY 0.446809 (-7885 2810);
FORCEPROP 2 LASTPROP $XRERR UNIQUE?
J 0
(-8125 2810);
DISPLAY 0.638298 (-8125 2810);
PAINT MONO (-8125 2810);
DISPLAY INVISIBLE (-8125 2810);
WIRE 16 -1 (-7500 2800)(-7500 2700);
WIRE 16 -1 (-7500 2700)(-7600 2700);
WIRE 16 -1 (-8100 2150)(-8350 2150);
WIRE 16 -1 (-8100 2150)(-8100 2550);
WIRE 16 -1 (-8350 2200)(-8350 2150);
WIRE 16 -1 (-8350 2150)(-8375 2150);
WIRE 16 -1 (-7400 2550)(-8100 2550);
FORCEPROP 2 LAST SIG_NAME PWRGD_CHH_CPU1_DIMM
J 0
(-7975 2560);
DISPLAY 0.489362 (-7975 2560);
FORCEPROP 2 LASTPROP $XRERR UNIQUE?
J 0
(-8215 2560);
DISPLAY 0.638298 (-8215 2560);
PAINT MONO (-8215 2560);
DISPLAY INVISIBLE (-8215 2560);
WIRE 16 -1 (-7400 2850)(-8200 2850);
FORCEPROP 2 LAST SIG_NAME I3C_SPD_DDRGL_CPU1_SDA
J 0
(-8210 2860);
DISPLAY 0.489362 (-8210 2860);
WIRE 16 -1 (-7400 2300)(-8000 2300);
FORCEPROP 2 LAST SIG_NAME TP_CHH_CPU1_DIMM_RFU_3
J 0
(-8010 2310);
DISPLAY 0.489362 (-8010 2310);
FORCEPROP 2 LASTPROP $XRERR UNIQUE?
J 0
(-8240 2300);
DISPLAY 0.638298 (-8240 2300);
PAINT MONO (-8240 2300);
DISPLAY INVISIBLE (-8240 2300);
WIRE 16 -1 (-7400 2350)(-8000 2350);
FORCEPROP 2 LAST SIG_NAME TP_CHH_CPU1_DIMM_RFU_4
J 0
(-8010 2360);
DISPLAY 0.489362 (-8010 2360);
FORCEPROP 2 LASTPROP $XRERR UNIQUE?
J 0
(-8240 2350);
DISPLAY 0.638298 (-8240 2350);
PAINT MONO (-8240 2350);
DISPLAY INVISIBLE (-8240 2350);
WIRE 16 -1 (-7400 2400)(-8000 2400);
FORCEPROP 2 LAST SIG_NAME TP_CHH_CPU1_DIMM_RFU_5
J 0
(-8010 2410);
DISPLAY 0.489362 (-8010 2410);
FORCEPROP 2 LASTPROP $XRERR UNIQUE?
J 0
(-8240 2400);
DISPLAY 0.638298 (-8240 2400);
PAINT MONO (-8240 2400);
DISPLAY INVISIBLE (-8240 2400);
WIRE 16 -1 (-7400 2900)(-8200 2900);
FORCEPROP 2 LAST SIG_NAME PD_CHH_CPU1_DIMM_SAA
J 0
(-8175 2910);
DISPLAY 0.489362 (-8175 2910);
WIRE 16 -1 (-8475 2950)(-7400 2950);
WIRE 16 -1 (-8475 3350)(-8475 2950);
WIRE 16 -1 (-8475 3375)(-8475 3350);
WIRE 16 -1 (-8575 3350)(-8475 3350);
WIRE 16 -1 (-8575 3325)(-8575 3350);
WIRE 16 -1 (-7400 3100)(-8050 3100);
FORCEPROP 2 LAST SIG_NAME M_H_CPU1_RESET_N
J 0
(-8035 3110);
DISPLAY 0.489362 (-8035 3110);
WIRE 16 -1 (-7400 3050)(-8050 3050);
FORCEPROP 2 LAST SIG_NAME M_H_CPU1_ALERT_N
J 0
(-8035 3060);
DISPLAY 0.489362 (-8035 3060);
WIRE 16 -1 (-2125 5200)(-1825 5200);
WIRE 16 -1 (-2125 5250)(-2125 5200);
WIRE 16 -1 (-1825 5250)(-2125 5250);
WIRE 16 -1 (-2125 5250)(-2125 5300);
WIRE 16 -1 (-1825 5300)(-2125 5300);
WIRE 16 -1 (-2125 5300)(-2125 6075);
WIRE 16 -1 (-2250 6075)(-2125 6075);
WIRE 16 -1 (-2250 6075)(-2825 6075);
WIRE 16 -1 (-2250 6075)(-2250 5975);
WIRE 16 -1 (-2825 6075)(-2825 6150);
WIRE 16 -1 (-2825 5975)(-2825 6075);
WIRE 16 -1 (-325 5300)(-325 5250);
WIRE 16 -1 (-325 5300)(-625 5300);
WIRE 16 -1 (-325 5250)(-325 5200);
WIRE 16 -1 (-325 5250)(-625 5250);
WIRE 16 -1 (-325 5200)(-325 5150);
WIRE 16 -1 (-325 5200)(-625 5200);
WIRE 16 -1 (-325 5150)(-625 5150);
WIRE 16 -1 (-325 5150)(-325 5100);
WIRE 16 -1 (-325 5100)(-325 5050);
WIRE 16 -1 (-325 5100)(-625 5100);
WIRE 16 -1 (-325 5050)(-325 5000);
WIRE 16 -1 (-325 5050)(-625 5050);
WIRE 16 -1 (-325 5000)(-325 4950);
WIRE 16 -1 (-325 5000)(-625 5000);
WIRE 16 -1 (-325 4950)(-325 4900);
WIRE 16 -1 (-325 4950)(-625 4950);
WIRE 16 -1 (-325 4900)(-325 4850);
WIRE 16 -1 (-325 4900)(-625 4900);
WIRE 16 -1 (-325 4850)(-325 4800);
WIRE 16 -1 (-325 4850)(-625 4850);
WIRE 16 -1 (-325 4800)(-325 4750);
WIRE 16 -1 (-325 4800)(-625 4800);
WIRE 16 -1 (-325 4750)(-325 4700);
WIRE 16 -1 (-325 4750)(-625 4750);
WIRE 16 -1 (-325 4700)(-325 4650);
WIRE 16 -1 (-325 4700)(-625 4700);
WIRE 16 -1 (-325 4650)(-325 4600);
WIRE 16 -1 (-325 4650)(-625 4650);
WIRE 16 -1 (-325 4600)(-325 4550);
WIRE 16 -1 (-325 4600)(-625 4600);
WIRE 16 -1 (-325 4550)(-325 4500);
WIRE 16 -1 (-325 4550)(-625 4550);
WIRE 16 -1 (-325 4500)(-325 4450);
WIRE 16 -1 (-325 4500)(-625 4500);
WIRE 16 -1 (-325 4450)(-325 4400);
WIRE 16 -1 (-325 4450)(-625 4450);
WIRE 16 -1 (-325 4400)(-325 4350);
WIRE 16 -1 (-325 4400)(-625 4400);
WIRE 16 -1 (-325 4350)(-325 4300);
WIRE 16 -1 (-325 4350)(-625 4350);
WIRE 16 -1 (-325 4300)(-325 4250);
WIRE 16 -1 (-325 4300)(-625 4300);
WIRE 16 -1 (-325 4250)(-325 4200);
WIRE 16 -1 (-325 4250)(-625 4250);
WIRE 16 -1 (-325 4200)(-325 4150);
WIRE 16 -1 (-325 4200)(-625 4200);
WIRE 16 -1 (-325 4150)(-325 4100);
WIRE 16 -1 (-325 4150)(-625 4150);
WIRE 16 -1 (-325 4100)(-625 4100);
WIRE 16 -1 (-325 4100)(-325 4050);
WIRE 16 -1 (-325 4050)(-325 4000);
WIRE 16 -1 (-325 4050)(-625 4050);
WIRE 16 -1 (-325 4000)(-325 3950);
WIRE 16 -1 (-325 4000)(-625 4000);
WIRE 16 -1 (-325 3950)(-325 3900);
WIRE 16 -1 (-325 3950)(-625 3950);
WIRE 16 -1 (-325 3900)(-325 3850);
WIRE 16 -1 (-325 3900)(-625 3900);
WIRE 16 -1 (-325 3850)(-325 3800);
WIRE 16 -1 (-325 3850)(-625 3850);
WIRE 16 -1 (-325 3800)(-325 3750);
WIRE 16 -1 (-325 3800)(-625 3800);
WIRE 16 -1 (-325 3750)(-325 3700);
WIRE 16 -1 (-325 3750)(-625 3750);
WIRE 16 -1 (-325 3700)(-325 3650);
WIRE 16 -1 (-325 3700)(-625 3700);
WIRE 16 -1 (-325 3650)(-325 3600);
WIRE 16 -1 (-325 3650)(-625 3650);
WIRE 16 -1 (-325 3600)(-325 3550);
WIRE 16 -1 (-325 3600)(-625 3600);
WIRE 16 -1 (-325 3550)(-325 3500);
WIRE 16 -1 (-325 3550)(-625 3550);
WIRE 16 -1 (-325 3500)(-325 3450);
WIRE 16 -1 (-325 3500)(-625 3500);
WIRE 16 -1 (-325 3450)(-325 3400);
WIRE 16 -1 (-325 3450)(-625 3450);
WIRE 16 -1 (-325 3400)(-325 3350);
WIRE 16 -1 (-325 3400)(-625 3400);
WIRE 16 -1 (-325 3350)(-325 3300);
WIRE 16 -1 (-325 3350)(-625 3350);
WIRE 16 -1 (-325 3300)(-325 3250);
WIRE 16 -1 (-325 3300)(-625 3300);
WIRE 16 -1 (-325 3250)(-325 3200);
WIRE 16 -1 (-325 3250)(-625 3250);
WIRE 16 -1 (-325 3200)(-325 3150);
WIRE 16 -1 (-325 3200)(-625 3200);
WIRE 16 -1 (-325 3150)(-325 3100);
WIRE 16 -1 (-325 3150)(-625 3150);
WIRE 16 -1 (-325 3100)(-625 3100);
WIRE 16 -1 (-325 3100)(-325 3050);
WIRE 16 -1 (-325 3050)(-325 3000);
WIRE 16 -1 (-325 3050)(-625 3050);
WIRE 16 -1 (-325 3000)(-325 2950);
WIRE 16 -1 (-325 3000)(-625 3000);
WIRE 16 -1 (-325 2950)(-325 2900);
WIRE 16 -1 (-325 2950)(-625 2950);
WIRE 16 -1 (-325 2900)(-325 2850);
WIRE 16 -1 (-325 2900)(-625 2900);
WIRE 16 -1 (-325 2850)(-325 2800);
WIRE 16 -1 (-325 2850)(-625 2850);
WIRE 16 -1 (-325 2800)(-325 2750);
WIRE 16 -1 (-325 2800)(-625 2800);
WIRE 16 -1 (-325 2750)(-325 2700);
WIRE 16 -1 (-325 2750)(-625 2750);
WIRE 16 -1 (-325 2700)(-325 2650);
WIRE 16 -1 (-325 2700)(-625 2700);
WIRE 16 -1 (-325 2650)(-325 2600);
WIRE 16 -1 (-325 2650)(-625 2650);
WIRE 16 -1 (-325 2600)(-325 2550);
WIRE 16 -1 (-325 2600)(-625 2600);
WIRE 16 -1 (-325 2550)(-325 2500);
WIRE 16 -1 (-325 2550)(-625 2550);
WIRE 16 -1 (-325 2500)(-325 2450);
WIRE 16 -1 (-325 2500)(-625 2500);
WIRE 16 -1 (-325 2450)(-325 2400);
WIRE 16 -1 (-325 2450)(-625 2450);
WIRE 16 -1 (-325 2400)(-325 2350);
WIRE 16 -1 (-325 2400)(-625 2400);
WIRE 16 -1 (-325 2350)(-325 2300);
WIRE 16 -1 (-325 2350)(-625 2350);
WIRE 16 -1 (-325 2300)(-325 2250);
WIRE 16 -1 (-325 2300)(-625 2300);
WIRE 16 -1 (-325 2250)(-325 2200);
WIRE 16 -1 (-325 2250)(-625 2250);
WIRE 16 -1 (-325 2200)(-325 2150);
WIRE 16 -1 (-325 2200)(-625 2200);
WIRE 16 -1 (-325 2150)(-325 2050);
WIRE 16 -1 (-325 2150)(-625 2150);
WIRE 16 -1 (-325 2050)(-325 2000);
WIRE 16 -1 (-325 2050)(-625 2050);
WIRE 16 -1 (-325 2000)(-325 1950);
WIRE 16 -1 (-325 2000)(-625 2000);
WIRE 16 -1 (-325 1950)(-325 1700);
WIRE 16 -1 (-325 1950)(-625 1950);
WIRE 16 -1 (-1825 2050)(-2125 2050);
WIRE 16 -1 (-2125 2100)(-2125 2050);
WIRE 16 -1 (-2125 2050)(-2125 1925);
WIRE 16 -1 (-1825 2100)(-2125 2100);
WIRE 16 -1 (-2125 2150)(-2125 2100);
WIRE 16 -1 (-1825 2150)(-2125 2150);
WIRE 16 -1 (-2125 2200)(-2125 2150);
WIRE 16 -1 (-1825 2200)(-2125 2200);
WIRE 16 -1 (-2125 2250)(-2125 2200);
WIRE 16 -1 (-1825 2250)(-2125 2250);
WIRE 16 -1 (-2125 2300)(-2125 2250);
WIRE 16 -1 (-1825 2300)(-2125 2300);
WIRE 16 -1 (-2125 2350)(-2125 2300);
WIRE 16 -1 (-1825 2350)(-2125 2350);
WIRE 16 -1 (-2125 2400)(-2125 2350);
WIRE 16 -1 (-1825 2400)(-2125 2400);
WIRE 16 -1 (-2125 2450)(-2125 2400);
WIRE 16 -1 (-1825 2450)(-2125 2450);
WIRE 16 -1 (-2125 2500)(-2125 2450);
WIRE 16 -1 (-1825 2500)(-2125 2500);
WIRE 16 -1 (-2125 2550)(-2125 2500);
WIRE 16 -1 (-1825 2550)(-2125 2550);
WIRE 16 -1 (-2125 2600)(-2125 2550);
WIRE 16 -1 (-1825 2600)(-2125 2600);
WIRE 16 -1 (-2125 2650)(-2125 2600);
WIRE 16 -1 (-1825 2650)(-2125 2650);
WIRE 16 -1 (-2125 2700)(-2125 2650);
WIRE 16 -1 (-1825 2700)(-2125 2700);
WIRE 16 -1 (-2125 2750)(-2125 2700);
WIRE 16 -1 (-1825 2750)(-2125 2750);
WIRE 16 -1 (-2125 2800)(-2125 2750);
WIRE 16 -1 (-1825 2800)(-2125 2800);
WIRE 16 -1 (-2125 2850)(-2125 2800);
WIRE 16 -1 (-1825 2850)(-2125 2850);
WIRE 16 -1 (-2125 2900)(-2125 2850);
WIRE 16 -1 (-1825 2900)(-2125 2900);
WIRE 16 -1 (-2125 2950)(-2125 2900);
WIRE 16 -1 (-1825 2950)(-2125 2950);
WIRE 16 -1 (-2125 3000)(-2125 2950);
WIRE 16 -1 (-1825 3000)(-2125 3000);
WIRE 16 -1 (-2125 3050)(-2125 3000);
WIRE 16 -1 (-1825 3050)(-2125 3050);
WIRE 16 -1 (-2125 3100)(-2125 3050);
WIRE 16 -1 (-1825 3100)(-2125 3100);
WIRE 16 -1 (-2125 3150)(-2125 3100);
WIRE 16 -1 (-1825 3150)(-2125 3150);
WIRE 16 -1 (-2125 3200)(-2125 3150);
WIRE 16 -1 (-1825 3200)(-2125 3200);
WIRE 16 -1 (-2125 3250)(-2125 3200);
WIRE 16 -1 (-1825 3250)(-2125 3250);
WIRE 16 -1 (-2125 3300)(-2125 3250);
WIRE 16 -1 (-1825 3300)(-2125 3300);
WIRE 16 -1 (-2125 3350)(-2125 3300);
WIRE 16 -1 (-1825 3350)(-2125 3350);
WIRE 16 -1 (-2125 3400)(-2125 3350);
WIRE 16 -1 (-1825 3400)(-2125 3400);
WIRE 16 -1 (-2125 3450)(-2125 3400);
WIRE 16 -1 (-1825 3450)(-2125 3450);
WIRE 16 -1 (-2125 3500)(-2125 3450);
WIRE 16 -1 (-1825 3500)(-2125 3500);
WIRE 16 -1 (-2125 3550)(-2125 3500);
WIRE 16 -1 (-1825 3550)(-2125 3550);
WIRE 16 -1 (-2125 3600)(-2125 3550);
WIRE 16 -1 (-1825 3600)(-2125 3600);
WIRE 16 -1 (-2125 3650)(-2125 3600);
WIRE 16 -1 (-1825 3650)(-2125 3650);
WIRE 16 -1 (-2125 3700)(-2125 3650);
WIRE 16 -1 (-1825 3700)(-2125 3700);
WIRE 16 -1 (-2125 3750)(-2125 3700);
WIRE 16 -1 (-1825 3750)(-2125 3750);
WIRE 16 -1 (-2125 3800)(-2125 3750);
WIRE 16 -1 (-1825 3800)(-2125 3800);
WIRE 16 -1 (-2125 3850)(-2125 3800);
WIRE 16 -1 (-1825 3850)(-2125 3850);
WIRE 16 -1 (-2125 3900)(-2125 3850);
WIRE 16 -1 (-1825 3900)(-2125 3900);
WIRE 16 -1 (-2125 3950)(-2125 3900);
WIRE 16 -1 (-1825 3950)(-2125 3950);
WIRE 16 -1 (-2125 4000)(-2125 3950);
WIRE 16 -1 (-1825 4000)(-2125 4000);
WIRE 16 -1 (-2125 4050)(-2125 4000);
WIRE 16 -1 (-2125 4100)(-2125 4050);
WIRE 16 -1 (-1825 4050)(-2125 4050);
WIRE 16 -1 (-1825 4100)(-2125 4100);
WIRE 16 -1 (-2125 4150)(-2125 4100);
WIRE 16 -1 (-1825 4150)(-2125 4150);
WIRE 16 -1 (-2125 4200)(-2125 4150);
WIRE 16 -1 (-1825 4200)(-2125 4200);
WIRE 16 -1 (-2125 4250)(-2125 4200);
WIRE 16 -1 (-1825 4250)(-2125 4250);
WIRE 16 -1 (-2125 4300)(-2125 4250);
WIRE 16 -1 (-1825 4300)(-2125 4300);
WIRE 16 -1 (-2125 4350)(-2125 4300);
WIRE 16 -1 (-1825 4350)(-2125 4350);
WIRE 16 -1 (-2125 4400)(-2125 4350);
WIRE 16 -1 (-1825 4400)(-2125 4400);
WIRE 16 -1 (-2125 4450)(-2125 4400);
WIRE 16 -1 (-1825 4450)(-2125 4450);
WIRE 16 -1 (-2125 4500)(-2125 4450);
WIRE 16 -1 (-1825 4500)(-2125 4500);
WIRE 16 -1 (-2125 4550)(-2125 4500);
WIRE 16 -1 (-1825 4550)(-2125 4550);
WIRE 16 -1 (-2125 4600)(-2125 4550);
WIRE 16 -1 (-1825 4600)(-2125 4600);
WIRE 16 -1 (-2125 4650)(-2125 4600);
WIRE 16 -1 (-1825 4650)(-2125 4650);
WIRE 16 -1 (-2125 4700)(-2125 4650);
WIRE 16 -1 (-1825 4700)(-2125 4700);
WIRE 16 -1 (-2125 4750)(-2125 4700);
WIRE 16 -1 (-1825 4750)(-2125 4750);
WIRE 16 -1 (-2125 4800)(-2125 4750);
WIRE 16 -1 (-1825 4800)(-2125 4800);
WIRE 16 -1 (-2125 4850)(-2125 4800);
WIRE 16 -1 (-1825 4850)(-2125 4850);
WIRE 16 -1 (-2125 4900)(-2125 4850);
WIRE 16 -1 (-1825 4900)(-2125 4900);
WIRE 16 -1 (-2125 4950)(-2125 4900);
WIRE 16 -1 (-1825 4950)(-2125 4950);
WIRE 16 -1 (-2125 5000)(-2125 4950);
WIRE 16 -1 (-1825 5000)(-2125 5000);
WIRE 16 -1 (-2125 5050)(-2125 5000);
WIRE 16 -1 (-1825 5050)(-2125 5050);
WIRE 16 -1 (-2125 5100)(-2125 5050);
WIRE 16 -1 (-1825 5100)(-2125 5100);
WIRE 16 -1 (-2125 5150)(-2125 5100);
WIRE 16 -1 (-1825 5150)(-2125 5150);
WIRE 16 -1 (-6200 4600)(-6000 4600);
WIRE 16 -1 (-6000 4650)(-6200 4650);
WIRE 16 -1 (-3625 4375)(-3275 4375);
WIRE 16 -1 (-3625 3375)(-3475 3375);
WIRE 16 -1 (-3625 3325)(-3275 3325);
WIRE 16 -1 (-3625 4425)(-3475 4425);
WIRE 16 -1 (-3475 4325)(-3625 4325);
WIRE 16 -1 (-3625 4275)(-3275 4275);
WIRE 16 -1 (-3625 3125)(-3275 3125);
WIRE 16 -1 (-3475 4225)(-3625 4225);
WIRE 16 -1 (-3475 3075)(-3625 3075);
WIRE 16 -1 (-3625 3025)(-3275 3025);
WIRE 16 -1 (-3625 4075)(-3275 4075);
WIRE 16 -1 (-3625 2975)(-3475 2975);
WIRE 16 -1 (-3625 2925)(-3275 2925);
WIRE 16 -1 (-3625 4025)(-3475 4025);
WIRE 16 -1 (-3625 3975)(-3275 3975);
WIRE 16 -1 (-3475 2875)(-3625 2875);
WIRE 16 -1 (-3625 2825)(-3275 2825);
WIRE 16 -1 (-3475 3925)(-3625 3925);
WIRE 16 -1 (-3625 3875)(-3275 3875);
WIRE 16 -1 (-3475 2775)(-3625 2775);
WIRE 16 -1 (-3625 2725)(-3275 2725);
WIRE 16 -1 (-3475 3825)(-3625 3825);
WIRE 16 -1 (-3625 3775)(-3275 3775);
WIRE 16 -1 (-3475 2675)(-3625 2675);
WIRE 16 -1 (-3625 2625)(-3275 2625);
WIRE 16 -1 (-3475 3725)(-3625 3725);
WIRE 16 -1 (-3625 3675)(-3275 3675);
WIRE 16 -1 (-3625 2575)(-3475 2575);
WIRE 16 -1 (-3625 2525)(-3275 2525);
WIRE 16 -1 (-3625 3625)(-3475 3625);
WIRE 16 -1 (-3625 3575)(-3275 3575);
WIRE 16 -1 (-3475 2475)(-3625 2475);
WIRE 16 -1 (-3625 2425)(-3275 2425);
WIRE 16 -1 (-3475 3525)(-3625 3525);
WIRE 16 -1 (-3625 3475)(-3275 3475);
WIRE 16 -1 (-3475 3175)(-3625 3175);
WIRE 16 -1 (-3625 3225)(-3275 3225);
WIRE 16 -1 (-3475 3275)(-3625 3275);
WIRE 16 -1 (-3475 4125)(-3625 4125);
WIRE 16 -1 (-3625 4175)(-3275 4175);
WIRE 16 -1 (-7400 5350)(-7600 5350);
WIRE 16 -1 (-7400 5300)(-7600 5300);
WIRE 16 -1 (-6000 5300)(-6200 5300);
WIRE 16 -1 (-6000 5350)(-6200 5350);
WIRE 16 -1 (-6000 5250)(-6200 5250);
WIRE 16 -1 (-7400 2150)(-8000 2150);
FORCEPROP 2 LAST SIG_NAME TP_CHH_CPU1_DIMM_RFU_0
J 0
(-8010 2160);
DISPLAY 0.489362 (-8010 2160);
FORCEPROP 2 LASTPROP $XRERR UNIQUE?
J 0
(-8240 2150);
DISPLAY 0.638298 (-8240 2150);
PAINT MONO (-8240 2150);
DISPLAY INVISIBLE (-8240 2150);
WIRE 16 -1 (-7400 2200)(-8000 2200);
FORCEPROP 2 LAST SIG_NAME TP_CHH_CPU1_DIMM_RFU_1
J 0
(-8010 2210);
DISPLAY 0.489362 (-8010 2210);
FORCEPROP 2 LASTPROP $XRERR UNIQUE?
J 0
(-8240 2200);
DISPLAY 0.638298 (-8240 2200);
PAINT MONO (-8240 2200);
DISPLAY INVISIBLE (-8240 2200);
WIRE 16 -1 (-7400 2250)(-8000 2250);
FORCEPROP 2 LAST SIG_NAME TP_CHH_CPU1_DIMM_RFU_2
J 0
(-8010 2260);
DISPLAY 0.489362 (-8010 2260);
FORCEPROP 2 LASTPROP $XRERR UNIQUE?
J 0
(-8240 2250);
DISPLAY 0.638298 (-8240 2250);
PAINT MONO (-8240 2250);
DISPLAY INVISIBLE (-8240 2250);
WIRE 16 -1 (-7400 2450)(-8000 2450);
FORCEPROP 2 LAST SIG_NAME TP_CHH_CPU1_DIMM_RFU_6
J 0
(-8010 2460);
DISPLAY 0.489362 (-8010 2460);
FORCEPROP 2 LASTPROP $XRERR UNIQUE?
J 0
(-8240 2450);
DISPLAY 0.638298 (-8240 2450);
PAINT MONO (-8240 2450);
DISPLAY INVISIBLE (-8240 2450);
WIRE 16 -1 (-7400 4550)(-8200 4550);
FORCEPROP 2 LAST SIG_NAME M_H_CPU1_SB_PAR
J 0
(-8150 4560);
DISPLAY 0.489362 (-8150 4560);
WIRE 16 -1 (-7400 4600)(-8200 4600);
FORCEPROP 2 LAST SIG_NAME M_H_CPU1_SA_PAR
J 0
(-8150 4610);
DISPLAY 0.489362 (-8150 4610);
WIRE 16 -1 (-7400 1950)(-8200 1950);
FORCEPROP 2 LAST SIG_NAME M_H_CPU1_SB_RSP<0>
J 0
(-8150 1960);
DISPLAY 0.489362 (-8150 1960);
WIRE 16 -1 (-7400 2000)(-8200 2000);
FORCEPROP 2 LAST SIG_NAME M_H_CPU1_SA_RSP<0>
J 0
(-8150 2010);
DISPLAY 0.489362 (-8150 2010);
WIRE 16 -1 (-6000 2200)(-6200 2200);
WIRE 16 -1 (-6000 2250)(-6200 2250);
WIRE 16 -1 (-6000 2300)(-6200 2300);
WIRE 16 -1 (-6200 2350)(-6000 2350);
WIRE 16 -1 (-6000 2400)(-6200 2400);
WIRE 16 -1 (-6000 2450)(-6200 2450);
WIRE 16 -1 (-6000 2500)(-6200 2500);
WIRE 16 -1 (-6200 2550)(-6000 2550);
WIRE 16 -1 (-6000 2600)(-6200 2600);
WIRE 16 -1 (-6000 2650)(-6200 2650);
WIRE 16 -1 (-6000 2700)(-6200 2700);
WIRE 16 -1 (-6200 2750)(-6000 2750);
WIRE 16 -1 (-6000 2800)(-6200 2800);
WIRE 16 -1 (-6000 2850)(-6200 2850);
WIRE 16 -1 (-6000 2900)(-6200 2900);
WIRE 16 -1 (-6200 2950)(-6000 2950);
WIRE 16 -1 (-6000 3000)(-6200 3000);
WIRE 16 -1 (-6000 3050)(-6200 3050);
WIRE 16 -1 (-6000 3100)(-6200 3100);
WIRE 16 -1 (-6200 3150)(-6000 3150);
WIRE 16 -1 (-6000 3200)(-6200 3200);
WIRE 16 -1 (-6000 3250)(-6200 3250);
WIRE 16 -1 (-6000 3300)(-6200 3300);
WIRE 16 -1 (-6200 3350)(-6000 3350);
WIRE 16 -1 (-6000 3400)(-6200 3400);
WIRE 16 -1 (-6000 3450)(-6200 3450);
WIRE 16 -1 (-6000 3500)(-6200 3500);
WIRE 16 -1 (-6200 3550)(-6000 3550);
WIRE 16 -1 (-6000 3600)(-6200 3600);
WIRE 16 -1 (-6000 3650)(-6200 3650);
WIRE 16 -1 (-6000 3700)(-6200 3700);
WIRE 16 -1 (-6200 3750)(-6000 3750);
WIRE 16 -1 (-6000 3850)(-6200 3850);
WIRE 16 -1 (-6000 3900)(-6200 3900);
WIRE 16 -1 (-6000 3950)(-6200 3950);
WIRE 16 -1 (-6200 4000)(-6000 4000);
WIRE 16 -1 (-6000 4050)(-6200 4050);
WIRE 16 -1 (-6000 4100)(-6200 4100);
WIRE 16 -1 (-6000 4150)(-6200 4150);
WIRE 16 -1 (-6200 4200)(-6000 4200);
WIRE 16 -1 (-6000 4250)(-6200 4250);
WIRE 16 -1 (-6000 4300)(-6200 4300);
WIRE 16 -1 (-6000 4350)(-6200 4350);
WIRE 16 -1 (-6200 4400)(-6000 4400);
WIRE 16 -1 (-6000 4450)(-6200 4450);
WIRE 16 -1 (-6000 4500)(-6200 4500);
WIRE 16 -1 (-6000 4550)(-6200 4550);
WIRE 16 -1 (-6000 4700)(-6200 4700);
WIRE 16 -1 (-6000 4750)(-6200 4750);
WIRE 16 -1 (-6200 4800)(-6000 4800);
WIRE 16 -1 (-6000 4850)(-6200 4850);
WIRE 16 -1 (-6000 4900)(-6200 4900);
WIRE 16 -1 (-6000 4950)(-6200 4950);
WIRE 16 -1 (-6200 5000)(-6000 5000);
WIRE 16 -1 (-6000 5050)(-6200 5050);
WIRE 16 -1 (-6000 5100)(-6200 5100);
WIRE 16 -1 (-6000 5150)(-6200 5150);
WIRE 16 -1 (-6200 5200)(-6000 5200);
WIRE 16 -1 (-7400 4300)(-8200 4300);
FORCEPROP 2 LAST SIG_NAME M_H_CPU1_SB_CS_N<1>
J 0
(-8150 4310);
DISPLAY 0.489362 (-8150 4310);
WIRE 16 -1 (-7400 4450)(-8200 4450);
FORCEPROP 2 LAST SIG_NAME M_H_CPU1_SA_CS_N<1>
J 0
(-8150 4460);
DISPLAY 0.489362 (-8150 4460);
WIRE 16 -1 (-7400 4250)(-8200 4250);
FORCEPROP 2 LAST SIG_NAME M_H_CPU1_SB_CS_N<0>
J 0
(-8150 4260);
DISPLAY 0.489362 (-8150 4260);
WIRE 16 -1 (-7400 4400)(-8200 4400);
FORCEPROP 2 LAST SIG_NAME M_H_CPU1_SA_CS_N<0>
J 0
(-8150 4410);
DISPLAY 0.489362 (-8150 4410);
WIRE 16 -1 (-7400 4150)(-8200 4150);
FORCEPROP 2 LAST SIG_NAME M_H_CPU1_CLK_DP<0>
J 0
(-8150 4160);
DISPLAY 0.489362 (-8150 4160);
WIRE 16 -1 (-7400 4100)(-8200 4100);
FORCEPROP 2 LAST SIG_NAME M_H_CPU1_CLK_DN<0>
J 0
(-8150 4110);
DISPLAY 0.489362 (-8150 4110);
WIRE 16 -1 (-7400 3200)(-7600 3200);
WIRE 16 -1 (-7400 3250)(-7600 3250);
WIRE 16 -1 (-7400 3300)(-7600 3300);
WIRE 16 -1 (-7400 3350)(-7600 3350);
WIRE 16 -1 (-7400 3400)(-7600 3400);
WIRE 16 -1 (-7400 3450)(-7600 3450);
WIRE 16 -1 (-7400 3500)(-7600 3500);
WIRE 16 -1 (-7400 3650)(-7600 3650);
WIRE 16 -1 (-7400 3750)(-7600 3750);
WIRE 16 -1 (-7400 3800)(-7600 3800);
WIRE 16 -1 (-7400 3900)(-7600 3900);
WIRE 16 -1 (-7400 3950)(-7600 3950);
WIRE 16 -1 (-7400 5000)(-7600 5000);
WIRE 16 -1 (-7400 5400)(-7600 5400);
WIRE 16 -1 (-7400 4950)(-7600 4950);
WIRE 16 -1 (-7400 4900)(-7600 4900);
WIRE 16 -1 (-7400 4850)(-7600 4850);
WIRE 16 -1 (-7400 5250)(-7600 5250);
WIRE 16 -1 (-7400 4800)(-7600 4800);
WIRE 16 -1 (-7400 5200)(-7600 5200);
WIRE 16 -1 (-7400 4750)(-7600 4750);
WIRE 16 -1 (-7400 5150)(-7600 5150);
WIRE 16 -1 (-7400 4700)(-7600 4700);
WIRE 16 -1 (-7400 5100)(-7600 5100);
WIRE 16 -1 (-7400 3550)(-7600 3550);
WIRE 16 -1 (-7400 3700)(-7600 3700);
WIRE 16 -1 (-7400 3850)(-7600 3850);
WIRE 16 -1 (-7400 4000)(-7600 4000);
WIRE 16 -1 (-6200 5400)(-6000 5400);
WIRE 16 -1 (-2250 5650)(-2825 5650);
WIRE 16 -1 (-2250 5650)(-2250 5775);
WIRE 16 -1 (-2825 5650)(-2825 5775);
WIRE 16 -1 (-2825 5650)(-2825 5575);
WIRE 16 -1 (-8575 2150)(-8975 2150);
FORCEPROP 2 LAST SIG_NAME PWRGD_CHGL_CPU1
J 0
(-8960 2160);
DISPLAY 0.489362 (-8960 2160);
WIRE 16 -1 (-6375 1250)(-6375 1175);
WIRE 16 -1 (-6375 1250)(-7100 1250);
FORCEPROP 2 LAST SIG_NAME PD_CHH_CPU1_DIMM_SAA
J 0
(-7085 1260);
DISPLAY 0.489362 (-7085 1260);
DOT 1 (-2125 5050);
DOT 1 (-2125 5100);
DOT 1 (-2125 4450);
DOT 1 (-2125 3400);
DOT 1 (-325 5250);
DOT 1 (-325 5200);
DOT 1 (-325 5150);
DOT 1 (-325 5100);
DOT 1 (-325 5050);
DOT 1 (-325 5000);
DOT 1 (-325 4950);
DOT 1 (-325 4900);
DOT 1 (-325 4850);
DOT 1 (-325 4750);
DOT 1 (-325 4800);
DOT 1 (-325 4700);
DOT 1 (-325 4650);
DOT 1 (-325 4600);
DOT 1 (-325 4550);
DOT 1 (-325 4500);
DOT 1 (-325 4450);
DOT 1 (-325 4400);
DOT 1 (-325 4350);
DOT 1 (-325 4300);
DOT 1 (-325 4250);
DOT 1 (-325 4200);
DOT 1 (-325 4150);
DOT 1 (-325 4100);
DOT 1 (-325 4050);
DOT 1 (-325 4000);
DOT 1 (-325 3950);
DOT 1 (-325 3900);
DOT 1 (-325 3850);
DOT 1 (-2125 5300);
DOT 1 (-2125 5250);
DOT 1 (-2125 4900);
DOT 1 (-2125 4850);
DOT 1 (-2125 4750);
DOT 1 (-2125 4800);
DOT 1 (-2125 4700);
DOT 1 (-2125 4650);
DOT 1 (-2125 4600);
DOT 1 (-2125 4550);
DOT 1 (-2125 4500);
DOT 1 (-2125 4400);
DOT 1 (-2125 4350);
DOT 1 (-2125 4300);
DOT 1 (-2125 4250);
DOT 1 (-2125 4200);
DOT 1 (-2125 4150);
DOT 1 (-2125 4100);
DOT 1 (-2125 4050);
DOT 1 (-2125 4000);
DOT 1 (-2125 3950);
DOT 1 (-2125 3850);
DOT 1 (-2125 3900);
DOT 1 (-325 3800);
DOT 1 (-325 3750);
DOT 1 (-325 3700);
DOT 1 (-325 3650);
DOT 1 (-325 3600);
DOT 1 (-325 3550);
DOT 1 (-325 3500);
DOT 1 (-325 3450);
DOT 1 (-325 3400);
DOT 1 (-325 3350);
DOT 1 (-325 3300);
DOT 1 (-325 3250);
DOT 1 (-325 3200);
DOT 1 (-325 3150);
DOT 1 (-325 3100);
DOT 1 (-325 3050);
DOT 1 (-325 3000);
DOT 1 (-325 2950);
DOT 1 (-325 2900);
DOT 1 (-325 2850);
DOT 1 (-325 2800);
DOT 1 (-325 2700);
DOT 1 (-325 2750);
DOT 1 (-325 2650);
DOT 1 (-325 2600);
DOT 1 (-325 2550);
DOT 1 (-325 2500);
DOT 1 (-325 2450);
DOT 1 (-325 2400);
DOT 1 (-325 2350);
DOT 1 (-325 2300);
DOT 1 (-325 2200);
DOT 1 (-325 2250);
DOT 1 (-325 2150);
DOT 1 (-325 2050);
DOT 1 (-325 2000);
DOT 1 (-325 1950);
DOT 1 (-2125 3800);
DOT 1 (-2125 3750);
DOT 1 (-2125 3700);
DOT 1 (-2125 3650);
DOT 1 (-2125 3600);
DOT 1 (-2125 3550);
DOT 1 (-2125 3450);
DOT 1 (-2125 3350);
DOT 1 (-2125 3300);
DOT 1 (-2125 3250);
DOT 1 (-2125 3200);
DOT 1 (-2125 3150);
DOT 1 (-2125 3100);
DOT 1 (-2125 3050);
DOT 1 (-2125 3000);
DOT 1 (-2125 2950);
DOT 1 (-2125 2900);
DOT 1 (-2125 2850);
DOT 1 (-2125 2800);
DOT 1 (-2125 2700);
DOT 1 (-2125 2750);
DOT 1 (-2125 2650);
DOT 1 (-2125 2600);
DOT 1 (-2125 2550);
DOT 1 (-2125 2500);
DOT 1 (-2125 2450);
DOT 1 (-2125 2400);
DOT 1 (-2125 2350);
DOT 1 (-2125 2300);
DOT 1 (-2125 2250);
DOT 1 (-2125 2200);
DOT 1 (-2125 2150);
DOT 1 (-2125 2100);
DOT 1 (-2125 2050);
DOT 1 (-8475 3350);
DOT 1 (-8350 2150);
DOT 1 (-2125 3500);
DOT 1 (-2825 5650);
DOT 1 (-2250 6075);
DOT 1 (-2825 6075);
DOT 1 (-2125 5000);
DOT 1 (-2125 4950);
QUIT
